G04 ================== begin FILE IDENTIFICATION RECORD ==================*
G04 Layout Name:  15105-sa.brd*
G04 Film Name:    SE_REF_L3*
G04 File Format:  Gerber RS274X*
G04 File Origin:  Cadence Allegro 16.5-S056*
G04 Origin Date:  Wed Nov 16 02:02:39 2016*
G04 *
G04 Layer:  BOARD GEOMETRY/SE_REF_L3_TBL*
G04 Layer:  BOARD GEOMETRY/SE_REF_L3_L3*
G04 Layer:  BOARD GEOMETRY/PANEL_OUTLINE*
G04 *
G04 Offset:    (0.00 0.00)*
G04 Mirror:    No*
G04 Mode:      Positive*
G04 Rotation:  0*
G04 FullContactRelief:  No*
G04 UndefLineWidth:     6.00*
G04 ================== end FILE IDENTIFICATION RECORD ====================*
%FSLAX35Y35*MOIN*%
%IR0*IPPOS*OFA0.00000B0.00000*MIA0B0*SFA1.00000B1.00000*%
%ADD10C,.02*%
%ADD11C,.005*%
%ADD12C,.006*%
G75*
%LPD*%
G75*
G54D10*
G01X1479970Y793988D02*
X2197470D01*
G01X1479970Y863288D02*
Y793988D01*
G01Y828638D02*
X2197470D01*
G01X1479970Y863288D02*
X2197470D01*
G01X1654970D02*
Y793988D01*
G01X1882470Y863288D02*
Y793988D01*
G01X1987470Y863288D02*
Y793988D01*
G01X2197470Y863288D02*
Y793988D01*
G54D11*
G01X40368Y377683D02*
X29051Y389000D01*
G01D02*
X25350D01*
G01X24123Y421207D02*
Y409061D01*
G01D02*
X24122Y409060D01*
G01D02*
Y407818D01*
G01D02*
X49549Y382391D01*
G01X22623Y420585D02*
Y409683D01*
G01D02*
X22622Y409682D01*
G01D02*
Y407196D01*
G01D02*
X22623Y407195D01*
G01D02*
Y404390D01*
G01D02*
X37450Y389563D01*
G01X25623Y421829D02*
Y408439D01*
G01D02*
X51048Y383014D01*
G01X35709Y428091D02*
X25570Y438230D01*
G01D02*
Y474809D01*
G01X28570Y476053D02*
Y439474D01*
G01D02*
X39059Y428985D01*
G01X11340Y571762D02*
Y433990D01*
G01D02*
X24123Y421207D01*
G01X31989Y427111D02*
X19489Y439611D01*
G01D02*
Y520232D01*
G01X27070Y475431D02*
Y438852D01*
G01D02*
X37559Y428363D01*
G01X9840Y634846D02*
Y433368D01*
G01D02*
X22623Y420585D01*
G01X33489Y427733D02*
X20989Y440233D01*
G01D02*
Y519610D01*
G01X12840Y571040D02*
Y434612D01*
G01D02*
X25623Y421829D01*
G01X25570Y474809D02*
X22489Y477890D01*
G01D02*
Y518988D01*
G01X25600Y479023D02*
X28570Y476053D01*
G01X23990Y518367D02*
Y478511D01*
G01D02*
X27070Y475431D01*
G01X28600Y480267D02*
X31570Y477297D01*
G01X27100Y479645D02*
X30070Y476675D01*
G01D02*
Y452030D01*
G01D02*
X35400Y446700D01*
G01X30100Y480889D02*
X33070Y477919D01*
G01X25600Y517855D02*
Y479023D01*
G01X28600Y516611D02*
Y480267D01*
G01X27100Y517233D02*
Y479645D01*
G01X53111Y539000D02*
X30100Y515989D01*
G01X22489Y518988D02*
X50002Y546501D01*
G01X51246Y543501D02*
X25600Y517855D01*
G01X19489Y520232D02*
X48758Y549501D01*
G01X29300Y539850D02*
Y574978D01*
G01X50624Y545001D02*
X23990Y518367D01*
G01X52490Y540501D02*
X28600Y516611D01*
G01X20989Y519610D02*
X49380Y548001D01*
G01X51868Y542001D02*
X27100Y517233D01*
G01X62400Y622822D02*
X11340Y571762D01*
G01X29300Y574978D02*
X62611Y608289D01*
G01X64250Y622450D02*
X12840Y571040D01*
G01X65350Y690356D02*
X9840Y634846D01*
G01X22810Y721110D02*
Y709160D01*
G01D02*
X31550Y700420D01*
G01X21250Y742650D02*
X24250Y739650D01*
G01D02*
Y722550D01*
G01D02*
X22810Y721110D01*
G01X39000Y299500D02*
Y297300D01*
G01D02*
X43300Y293000D01*
G01D02*
X63983D01*
G01X61800Y306900D02*
X60900Y306000D01*
G01D02*
X41900D01*
G01D02*
X38800Y302900D01*
G01X35300Y303100D02*
Y295800D01*
G01D02*
X48150Y282950D01*
G01D02*
X100732D01*
G01X71726Y348700D02*
X53182Y367244D01*
G01D02*
X41371D01*
G01D02*
X38016Y370599D01*
G01D02*
Y372133D01*
G01D02*
X40368Y374485D01*
G01D02*
Y377683D01*
G01X39866Y371366D02*
X42488Y368744D01*
G01D02*
X53895D01*
G01D02*
X72129Y350510D01*
G01X49550Y382001D02*
Y377733D01*
G01D02*
X73773Y353510D01*
G01X47105Y378056D02*
X73151Y352010D01*
G01X51050Y381467D02*
X74205Y358312D01*
G01X51617Y413500D02*
X60793Y404322D01*
G01D02*
X63522Y401592D01*
G01D02*
X71590Y393524D01*
G01X65714Y384777D02*
X41717Y408774D01*
G01D02*
Y411125D01*
G01D02*
X35709Y417133D01*
G01X52678Y414561D02*
X61854Y405383D01*
G01D02*
X64584Y402653D01*
G01X47025Y411722D02*
X48363Y410385D01*
G01D02*
X67090Y391658D01*
G01X49549Y382391D02*
X49550Y382001D01*
G01X74939Y367500D02*
X62714Y379725D01*
G01D02*
Y383533D01*
G01D02*
X38717Y407530D01*
G01D02*
Y408069D01*
G01D02*
X38715Y408071D01*
G01D02*
Y409313D01*
G01D02*
X38716Y409314D01*
G01D02*
Y409616D01*
G01D02*
X31989Y416343D01*
G01X43217Y411747D02*
Y409396D01*
G01D02*
X67214Y385399D01*
G01X55508Y417391D02*
X64684Y408213D01*
G01X48574Y414420D02*
X52144Y410850D01*
G01D02*
X59732Y403261D01*
G01D02*
X62461Y400531D01*
G01D02*
X70090Y392902D01*
G01X37450Y389563D02*
Y388733D01*
G01D02*
X38533Y387650D01*
G01D02*
X39363D01*
G01D02*
X47105Y379908D01*
G01D02*
Y378056D01*
G01X64214Y384155D02*
X40217Y408152D01*
G01D02*
Y408691D01*
G01D02*
X40216Y408692D01*
G01D02*
Y409934D01*
G01D02*
X40217Y409935D01*
G01D02*
Y410238D01*
G01D02*
X33489Y416966D01*
G01X51048Y383014D02*
X51050Y382238D01*
G01D02*
Y381467D01*
G01X48087Y412783D02*
X49424Y411447D01*
G01D02*
X58671Y402200D01*
G01D02*
X61400Y399470D01*
G01D02*
X68590Y392280D01*
G01X39561Y447188D02*
Y434849D01*
G01D02*
X45930Y428480D01*
G01D02*
Y421300D01*
G01D02*
X48450Y418780D01*
G01D02*
Y416670D01*
G01D02*
X49216Y415904D01*
G01D02*
Y415902D01*
G01D02*
X49717Y415400D01*
G01D02*
X51617Y413500D01*
G01X35709Y426942D02*
Y428091D01*
G01Y417133D02*
Y426942D01*
G01X41322Y447549D02*
Y439000D01*
G01D02*
X50717Y429605D01*
G01D02*
Y424722D01*
G01D02*
X49950Y423954D01*
G01D02*
Y417292D01*
G01D02*
X50716Y416526D01*
G01D02*
Y416524D01*
G01D02*
X51273Y415966D01*
G01D02*
X52678Y414561D01*
G01X39059Y428985D02*
Y418027D01*
G01D02*
X44717Y412369D01*
G01D02*
X46379D01*
G01D02*
X46448Y412300D01*
G01D02*
X47025Y411722D01*
G01X31989Y416343D02*
Y427111D01*
G01X37559Y428363D02*
Y419893D01*
G01D02*
X37558Y419892D01*
G01D02*
Y418650D01*
G01D02*
X37557Y418649D01*
G01D02*
Y417407D01*
G01D02*
X43217Y411747D01*
G01X41570Y453136D02*
X51800Y442906D01*
G01D02*
Y442905D01*
G01D02*
X54718Y439987D01*
G01D02*
Y431030D01*
G01D02*
X54717Y431029D01*
G01D02*
Y423570D01*
G01D02*
X53950Y422296D01*
G01D02*
Y418950D01*
G01D02*
X54718Y418182D01*
G01D02*
Y418181D01*
G01D02*
X55508Y417391D01*
G01X37600Y447027D02*
Y434688D01*
G01D02*
X44000Y428288D01*
G01D02*
Y420919D01*
G01D02*
X46950Y417969D01*
G01D02*
Y416048D01*
G01D02*
X47715Y415283D01*
G01D02*
Y415281D01*
G01D02*
X47718Y415278D01*
G01D02*
X48574Y414420D01*
G01X33489Y416966D02*
Y427733D01*
G01X61150Y446928D02*
X63718Y444360D01*
G01D02*
Y427300D01*
G01D02*
X63719Y427299D01*
G01D02*
Y427258D01*
G01D02*
X67043Y423934D01*
G01X35400Y446700D02*
Y434766D01*
G01D02*
X40560Y429606D01*
G01D02*
Y418899D01*
G01D02*
X45590Y413869D01*
G01D02*
X47003D01*
G01D02*
X47242Y413630D01*
G01D02*
X47511Y413360D01*
G01D02*
X48087Y412783D01*
G01X33070Y477919D02*
Y473630D01*
G01D02*
X35750Y470950D01*
G01D02*
Y467199D01*
G01D02*
X33400Y464849D01*
G01D02*
Y453349D01*
G01D02*
X39561Y447188D01*
G01X31800Y481311D02*
X34570Y478541D01*
G01D02*
Y474631D01*
G01D02*
X37250Y471951D01*
G01D02*
Y466577D01*
G01D02*
X34900Y464227D01*
G01D02*
Y453971D01*
G01D02*
X41322Y447549D01*
G01X65218Y444982D02*
X62650Y447550D01*
G01D02*
Y470124D01*
G01D02*
X60443Y472331D01*
G01D02*
Y476413D01*
G01D02*
X56019Y480838D01*
G01X40079Y483991D02*
Y477039D01*
G01D02*
X41570Y475548D01*
G01D02*
Y453136D01*
G01X31570Y477297D02*
Y453057D01*
G01D02*
X37600Y447027D01*
G01X52826Y481909D02*
X58943Y475791D01*
G01D02*
Y471709D01*
G01D02*
X61150Y469502D01*
G01D02*
Y446928D01*
G01X57550Y518684D02*
Y493733D01*
G01D02*
X59783Y491500D01*
G01D02*
X61327D01*
G01D02*
X62900Y489927D01*
G01D02*
Y487200D01*
G01D02*
X69608Y480492D01*
G01X30100Y515989D02*
Y480889D01*
G01X31800Y515566D02*
Y481311D01*
G01X69099Y507380D02*
X61080D01*
G01D02*
X60150Y506450D01*
G01X64500Y490449D02*
X61849Y493100D01*
G01D02*
X60305D01*
G01D02*
X59050Y494355D01*
G01D02*
Y495889D01*
G01D02*
X65861Y502700D01*
G01X56019Y480838D02*
Y482980D01*
G01D02*
X52071Y486928D01*
G01D02*
Y491436D01*
G01D02*
X50907Y492600D01*
G01D02*
X49482D01*
G01D02*
X48290Y493792D01*
G01D02*
Y511546D01*
G01D02*
X57778Y521034D01*
G01X37788Y515896D02*
Y500822D01*
G01D02*
X37789Y500821D01*
G01D02*
Y486282D01*
G01D02*
X37790Y486281D01*
G01D02*
Y486280D01*
G01D02*
X40079Y483991D01*
G01X56278Y521656D02*
X46790Y512168D01*
G01D02*
Y490011D01*
G01D02*
X52826Y483975D01*
G01D02*
Y481909D01*
G01X69090Y521850D02*
X62608D01*
G01D02*
X62255Y521497D01*
G01D02*
X62254D01*
G01D02*
X62253Y521496D01*
G01D02*
X60361D01*
G01D02*
X59278Y520413D01*
G01D02*
Y520412D01*
G01D02*
X57550Y518684D01*
G01X71250Y545050D02*
X61053D01*
G01D02*
X55002Y538999D01*
G01D02*
X54354D01*
G01D02*
X54353Y539000D01*
G01D02*
X53111D01*
G01X61128Y519646D02*
X61282Y519800D01*
G01D02*
X62700D01*
G01D02*
X63250Y520350D01*
G01D02*
X68467D01*
G01X51893Y546501D02*
X59611Y554219D01*
G01X66517Y541000D02*
X59125D01*
G01D02*
X55624Y537499D01*
G01D02*
X53733D01*
G01D02*
X53730Y537496D01*
G01D02*
X53729D01*
G01D02*
X33789Y517556D01*
G01D02*
Y517555D01*
G01D02*
X31800Y515566D01*
G01X60205Y550569D02*
X53137Y543501D01*
G01D02*
X51246D01*
G01X57778Y521034D02*
Y521035D01*
G01D02*
X59739Y522996D01*
G01D02*
X61631D01*
G01D02*
X61632Y522997D01*
G01D02*
X61633D01*
G01D02*
X61986Y523350D01*
G01D02*
X69712D01*
G01X59583Y552069D02*
X52515Y545001D01*
G01D02*
X50624D01*
G01X61800Y537000D02*
X60783D01*
G01D02*
X57281Y533498D01*
G01D02*
X55390D01*
G01D02*
X55388Y533496D01*
G01D02*
X55387D01*
G01D02*
X37789Y515898D01*
G01D02*
Y515897D01*
G01D02*
X37788Y515896D01*
G01X61675Y546550D02*
X61674Y546551D01*
G01X60432D02*
X54381Y540500D01*
G01D02*
X53733D01*
G01D02*
X53732Y540501D01*
G01D02*
X52490D01*
G01X61870Y515670D02*
X66222Y511318D01*
G01X75337Y524850D02*
X61364D01*
G01D02*
X61011Y524497D01*
G01D02*
X61010D01*
G01D02*
X61009Y524496D01*
G01D02*
X59117D01*
G01D02*
X56278Y521657D01*
G01D02*
Y521656D01*
G01X60478Y548719D02*
X53760Y542001D01*
G01D02*
X51868D01*
G01X50002Y546501D02*
X51893D01*
G01X59611Y554219D02*
X73836D01*
G01X67731Y550569D02*
X60205D01*
G01X48758Y549501D02*
X49695D01*
G01D02*
X59124Y558930D01*
G01D02*
X63000D01*
G01X75731Y552069D02*
X59583D01*
G01X70950Y546550D02*
X61675D01*
G01X61674Y546551D02*
X60432D01*
G01X49380Y548001D02*
X50317D01*
G01D02*
X59316Y557000D01*
G01D02*
X74000D01*
G01X65381Y548719D02*
X60478D01*
G01X62400Y624500D02*
Y622822D01*
G01X63300Y634800D02*
X64250Y633850D01*
G01X31550Y700420D02*
X39690D01*
G01D02*
X42910Y697200D01*
G01D02*
X63300D01*
G01X63983Y293000D02*
X65383Y294400D01*
G01D02*
X77617D01*
G01D02*
X79017Y293000D01*
G01D02*
X94800D01*
G01D02*
X95700Y293900D01*
G01X101001Y329600D02*
X96550Y334051D01*
G01D02*
Y336778D01*
G01D02*
X87078Y346250D01*
G01X87649Y347801D02*
X98050Y337400D01*
G01X90067Y349301D02*
X106718Y332650D01*
G01X87078Y346250D02*
X85650D01*
G01D02*
X83200Y348700D01*
G01D02*
X71726D01*
G01X71590Y392113D02*
X94893Y368810D01*
G01D02*
X96135D01*
G01D02*
X96136Y368811D01*
G01D02*
X101330D01*
G01X105006Y352100D02*
X95307Y361799D01*
G01D02*
X93417D01*
G01D02*
X93416Y361800D01*
G01D02*
X93200D01*
G01D02*
X79979Y375021D01*
G01D02*
X71795D01*
G01D02*
X65714Y381102D01*
G01X73090Y392735D02*
X95514Y370311D01*
G01D02*
X101952D01*
G01X72129Y350510D02*
X83512D01*
G01D02*
X86221Y347801D01*
G01D02*
X87649D01*
G01X70171Y381975D02*
X75624Y376522D01*
G01D02*
X80701D01*
G01D02*
X93923Y363300D01*
G01D02*
X94038D01*
G01D02*
X94039Y363299D01*
G01D02*
X95281D01*
G01D02*
X95282Y363300D01*
G01D02*
X95928D01*
G01D02*
X105628Y353600D01*
G01X73773Y353510D02*
X84756D01*
G01D02*
X87465Y350801D01*
G01D02*
X90689D01*
G01D02*
X104040Y337450D01*
G01X107294Y345300D02*
X93943Y358651D01*
G01D02*
X90730D01*
G01D02*
X81881Y367500D01*
G01D02*
X74939D01*
G01X70090Y391491D02*
X94272Y367309D01*
G01D02*
X94273D01*
G01D02*
X95082Y366500D01*
G01D02*
X96972D01*
G01D02*
X106872Y356600D01*
G01X73151Y352010D02*
X84134D01*
G01D02*
X86843Y349301D01*
G01D02*
X90067D01*
G01X104384Y350600D02*
X94833Y360151D01*
G01D02*
X92248D01*
G01D02*
X78879Y373520D01*
G01D02*
X71174D01*
G01D02*
X64214Y380480D01*
G01X74205Y358312D02*
Y356378D01*
G01D02*
X75572Y355011D01*
G01D02*
X85389D01*
G01D02*
X88099Y352301D01*
G01D02*
X91312D01*
G01D02*
X104663Y338950D01*
G01X68590Y390869D02*
X93650Y365809D01*
G01D02*
X93651D01*
G01D02*
X94660Y364800D01*
G01D02*
X96550D01*
G01D02*
X106250Y355100D01*
G01X87863Y412309D02*
Y410299D01*
G01D02*
X87910Y410252D01*
G01D02*
X94494Y403666D01*
G01D02*
X96551Y401611D01*
G01D02*
X100267D01*
G01X71590Y393524D02*
Y392113D01*
G01X65714Y381102D02*
Y384777D01*
G01X64584Y402653D02*
X65494Y401742D01*
G01D02*
X73090Y394146D01*
G01D02*
Y392735D01*
G01X100889Y403111D02*
X97173D01*
G01D02*
X95729Y404553D01*
G01D02*
X95728Y404555D01*
G01D02*
X89411Y410873D01*
G01D02*
Y412883D01*
G01X67090Y391658D02*
Y390247D01*
G01D02*
X70171Y387166D01*
G01D02*
Y381975D01*
G01X97676Y396587D02*
X94494D01*
G01D02*
X93500Y397581D01*
G01D02*
X86332Y404754D01*
G01D02*
X84372Y406715D01*
G01D02*
X82422Y408667D01*
G01D02*
X82261Y408828D01*
G01D02*
Y410838D01*
G01D02*
X65219Y427880D01*
G01X99245Y408111D02*
X96930Y410426D01*
G01D02*
Y412564D01*
G01X67214Y385399D02*
Y382615D01*
G01D02*
X68365Y381464D01*
G01X64684Y408213D02*
X65985Y406911D01*
G01D02*
X77090Y395806D01*
G01D02*
Y394393D01*
G01D02*
X81583Y389900D01*
G01D02*
X85419D01*
G01D02*
X100919Y374400D01*
G01X70090Y392902D02*
Y391491D01*
G01X64214Y380480D02*
Y384155D01*
G01X67043Y419792D02*
X78500Y408335D01*
G01D02*
X80154D01*
G01D02*
X84922Y403567D01*
G01D02*
X84923D01*
G01D02*
X93405Y395085D01*
G01D02*
X94448D01*
G01D02*
X95146Y395086D01*
G01D02*
X95530D01*
G01D02*
X95531Y395085D01*
G01D02*
X95547D01*
G01D02*
X104201Y386431D01*
G01X68590Y392280D02*
Y390869D01*
G01X71500Y445792D02*
X73275Y444017D01*
G01D02*
Y426902D01*
G01D02*
X87423Y412754D01*
G01D02*
Y412749D01*
G01D02*
X87863Y412309D01*
G01X89411Y412883D02*
X88923Y413371D01*
G01D02*
Y413376D01*
G01D02*
X74775Y427524D01*
G01D02*
Y444639D01*
G01D02*
X73000Y446414D01*
G01X65219Y427880D02*
Y444803D01*
G01D02*
X65218Y444982D01*
G01X96930Y412564D02*
X83909Y425585D01*
G01D02*
Y431839D01*
G01D02*
X81139Y434608D01*
G01D02*
X79775Y435972D01*
G01D02*
Y446711D01*
G01X67043Y423934D02*
Y419792D01*
G01X69608Y480492D02*
Y467292D01*
G01D02*
X71500Y465400D01*
G01D02*
Y445792D01*
G01X73000Y446414D02*
Y471700D01*
G01D02*
X71108Y473592D01*
G01D02*
Y481292D01*
G01X79775Y446711D02*
X78000Y448486D01*
G01D02*
Y476836D01*
G01D02*
X66100Y488736D01*
G01X112920Y509818D02*
X71537D01*
G01D02*
X69099Y507380D01*
G01X71108Y481292D02*
X64500Y487900D01*
G01D02*
Y490449D01*
G01X65861Y502700D02*
X66541D01*
G01D02*
X72159Y508318D01*
G01D02*
X111326D01*
G01X66100Y488736D02*
Y491549D01*
G01D02*
X65850Y491799D01*
G01D02*
Y499887D01*
G01D02*
X68182Y502219D01*
G01D02*
X70910D01*
G01X67700Y499120D02*
X73548Y493272D01*
G01D02*
X89521D01*
G01D02*
X91030Y491763D01*
G01D02*
X105205D01*
G01X66222Y511318D02*
X116282D01*
G01X67162Y515142D02*
X67658D01*
G01D02*
X69150Y513650D01*
G01D02*
X119551D01*
G01X121673Y523170D02*
X80987D01*
G01D02*
X78467Y520650D01*
G01D02*
X70290D01*
G01D02*
X69090Y521850D01*
G01X73700Y542600D02*
X71250Y545050D01*
G01X68467Y520350D02*
X72167Y516650D01*
G01D02*
X78467D01*
G01D02*
X83437Y521620D01*
G01D02*
X122316D01*
G01X74300Y533600D02*
X74451Y533751D01*
G01D02*
X81892D01*
G01D02*
X82993Y532650D01*
G01D02*
X119123D01*
G01X70000Y542500D02*
X68017D01*
G01D02*
X66517Y541000D01*
G01X69712Y523350D02*
X70562Y522500D01*
G01D02*
X77700D01*
G01X129571Y515271D02*
X79210D01*
G01D02*
X79089Y515150D01*
G01D02*
X71050D01*
G01D02*
X67700Y518500D01*
G01X73700Y549300D02*
X70950Y546550D01*
G01X77372Y526885D02*
X75337Y524850D01*
G01X73836Y554219D02*
X76407Y556790D01*
G01D02*
X77807D01*
G01D02*
X81304Y560287D01*
G01D02*
Y568618D01*
G01D02*
X84076Y571390D01*
G01D02*
Y577924D01*
G01D02*
X84226D01*
G01X69100Y549200D02*
X67731Y550569D01*
G01X77400Y550400D02*
X75731Y552069D01*
G01X69500Y586000D02*
X69700Y586200D01*
G01D02*
X87000D01*
G01D02*
X92000Y591200D01*
G01X64250Y633850D02*
Y622450D01*
G01X100732Y282950D02*
X102499Y281183D01*
G01X134800Y329600D02*
X101001D01*
G01X98050Y337400D02*
Y334849D01*
G01D02*
X101749Y331150D01*
G01D02*
X117727D01*
G01D02*
X118477Y331900D01*
G01D02*
X165221D01*
G01X104040Y337450D02*
X107484D01*
G01D02*
X110784Y334150D01*
G01D02*
X116151D01*
G01D02*
X116901Y334900D01*
G01D02*
X167675D01*
G01X106718Y332650D02*
X117105D01*
G01D02*
X117855Y333400D01*
G01D02*
X166457D01*
G01X104663Y338950D02*
X108106D01*
G01D02*
X109206Y337850D01*
G01D02*
X114467D01*
G01D02*
X115217Y337100D01*
G01D02*
Y337098D01*
G01D02*
X167713D01*
G01X101330Y368811D02*
X101341Y368800D01*
G01D02*
X116726Y353500D01*
G01D02*
X116864Y353499D01*
G01D02*
X118106D01*
G01D02*
X118107Y353500D01*
G01D02*
X178800D01*
G01X171870Y346930D02*
X117158D01*
G01D02*
X117157Y346929D01*
G01D02*
X114671D01*
G01D02*
X109500Y352100D01*
G01D02*
X105006D01*
G01X101952Y370311D02*
X101963Y370300D01*
G01D02*
X102185D01*
G01D02*
X117485Y355000D01*
G01D02*
X180610D01*
G01X105628Y353600D02*
X110122D01*
G01D02*
X115293Y348429D01*
G01D02*
X116535D01*
G01D02*
X116536Y348430D01*
G01D02*
X173178D01*
G01X139273Y374952D02*
X121282D01*
G01D02*
X105561Y390673D01*
G01X111900Y344200D02*
X111837D01*
G01D02*
X110737Y345300D01*
G01D02*
X107294D01*
G01X100919Y374400D02*
X103743D01*
G01D02*
X114343Y363800D01*
G01D02*
X117872D01*
G01D02*
X122672Y359000D01*
G01D02*
X185932D01*
G01X106872Y356600D02*
X111366D01*
G01D02*
X116183Y351783D01*
G01D02*
X177916D01*
G01X171020Y345430D02*
X117780D01*
G01D02*
X117779Y345429D01*
G01D02*
X114049D01*
G01D02*
X108878Y350600D01*
G01D02*
X104384D01*
G01X109697Y383312D02*
X119557Y373452D01*
G01D02*
X138651D01*
G01X106250Y355100D02*
X110744D01*
G01D02*
X115914Y349930D01*
G01D02*
X177154D01*
G01X100267Y401611D02*
X105605Y396273D01*
G01D02*
X111384D01*
G01D02*
X121303Y386354D01*
G01D02*
Y382978D01*
G01D02*
X124329Y379952D01*
G01D02*
X141346D01*
G01X141968Y381452D02*
X124951D01*
G01D02*
X122803Y383600D01*
G01D02*
Y386976D01*
G01D02*
X111643Y398136D01*
G01D02*
X108403D01*
G01D02*
X108402Y398135D01*
G01D02*
X106332D01*
G01D02*
X106294Y398173D01*
G01D02*
X105827D01*
G01D02*
X100889Y403111D01*
G01X105561Y390673D02*
X103590D01*
G01D02*
X97676Y396587D01*
G01X136863Y388679D02*
X128172D01*
G01D02*
X113678Y403173D01*
G01D02*
X107899D01*
G01D02*
X102961Y408111D01*
G01D02*
X99245D01*
G01X104201Y386431D02*
Y386415D01*
G01D02*
X107304Y383312D01*
G01D02*
X109697D01*
G01X131800Y439100D02*
X120000Y450900D01*
G01X134800Y426049D02*
X129500Y431349D01*
G01D02*
Y437300D01*
G01D02*
X118000Y448800D01*
G01X117678Y447000D02*
X128000Y436678D01*
G01D02*
Y430727D01*
G01D02*
X133300Y425427D01*
G01X120000Y450900D02*
Y451285D01*
G01X123696Y454452D02*
X126373Y457129D01*
G01D02*
Y476813D01*
G01D02*
X129570Y480010D01*
G01X118000Y448800D02*
X111200D01*
G01D02*
X109000Y451000D01*
G01D02*
Y455500D01*
G01D02*
X106800Y457700D01*
G01D02*
Y463800D01*
G01D02*
X101200Y469400D01*
G01D02*
Y470400D01*
G01X107900Y448900D02*
X109800Y447000D01*
G01D02*
X117678D01*
G01X129520Y448660D02*
X129630D01*
G01D02*
X131529Y450559D01*
G01X119551Y513650D02*
X121030Y512171D01*
G01D02*
X129520D01*
G01D02*
X131121Y510570D01*
G01X118500Y504238D02*
X112920Y509818D01*
G01X111326Y508318D02*
X115373Y504271D01*
G01X129570Y480010D02*
Y493272D01*
G01D02*
X131121Y494823D01*
G01X105205Y491763D02*
X106714Y493272D01*
G01D02*
X126420D01*
G01D02*
X127971Y494823D01*
G01X116282Y511318D02*
X119670Y507930D01*
G01D02*
X127355D01*
G01D02*
X130985Y504300D01*
G01X122316Y521620D02*
X123866Y523170D01*
G01D02*
X124823D01*
G01X119123Y532650D02*
X120706Y531067D01*
G01D02*
X131764D01*
G01X131121Y513721D02*
X129571Y515271D01*
G01X107000Y717800D02*
X142250Y682550D01*
G01X141346Y379952D02*
X144149Y377149D01*
G01D02*
X205840D01*
G01X202315Y371753D02*
X164253D01*
G01D02*
X162078Y369578D01*
G01D02*
X152657D01*
G01D02*
X150629Y371606D01*
G01D02*
X142619D01*
G01D02*
X139273Y374952D01*
G01X138651Y373452D02*
X141997Y370106D01*
G01D02*
X150006D01*
G01D02*
X152034Y368078D01*
G01D02*
X163848D01*
G01D02*
X165673Y369903D01*
G01X211186Y378649D02*
X144771D01*
G01D02*
X141968Y381452D01*
G01X210333Y380149D02*
X156843D01*
G01D02*
X156842Y380150D01*
G01D02*
X155600D01*
G01D02*
X155599Y380151D01*
G01D02*
X153113D01*
G01D02*
X153111Y380149D01*
G01D02*
X145393D01*
G01D02*
X136863Y388679D01*
G01X145901Y441262D02*
X148015Y443376D01*
G01D02*
Y445643D01*
G01X178807Y418367D02*
X146633D01*
G01D02*
X138900Y426100D01*
G01D02*
Y428400D01*
G01D02*
X131800Y435500D01*
G01D02*
Y439100D01*
G01X197513Y429656D02*
X152422D01*
G01D02*
X142383Y439695D01*
G01D02*
Y446521D01*
G01X135150Y449450D02*
Y434897D01*
G01D02*
X146747Y423300D01*
G01D02*
X177678D01*
G01X140883Y447143D02*
Y438000D01*
G01D02*
X150727Y428156D01*
G01D02*
X198135D01*
G01X202006Y425156D02*
X147644D01*
G01D02*
X138514Y434286D01*
G01D02*
X137883D01*
G01D02*
X137000Y435169D01*
G01D02*
Y436700D01*
G01X136500Y417400D02*
X134800Y419100D01*
G01D02*
Y426049D01*
G01X133300Y425427D02*
Y417800D01*
G01D02*
X136727Y414373D01*
G01D02*
X178531D01*
G01X153100Y439000D02*
Y445683D01*
G01X143883Y445899D02*
Y440317D01*
G01D02*
X144800Y439400D01*
G01D02*
X149180D01*
G01D02*
X152978Y435602D01*
G01X198757Y426656D02*
X149644D01*
G01D02*
X139383Y436917D01*
G01D02*
Y436934D01*
G01D02*
X137169Y439148D01*
G01D02*
Y443945D01*
G01D02*
X139194Y445970D01*
G01X148015Y445643D02*
X147988Y445670D01*
G01D02*
Y452534D01*
G01D02*
X151570Y456116D01*
G01D02*
Y490124D01*
G01X142383Y446521D02*
X144112Y448250D01*
G01D02*
Y477411D01*
G01D02*
X143547Y477976D01*
G01X137000Y451300D02*
X135150Y449450D01*
G01X141345Y482545D02*
Y469222D01*
G01D02*
X142612Y467955D01*
G01D02*
Y448872D01*
G01D02*
X140883Y447143D01*
G01X159082Y452509D02*
X161019Y454446D01*
G01D02*
Y490124D01*
G01X137344Y446737D02*
X137345Y446738D01*
G01D02*
Y448245D01*
G01D02*
X138945Y449845D01*
G01D02*
Y468622D01*
G01D02*
X139000Y468677D01*
G01D02*
Y490103D01*
G01X131529Y450559D02*
X131780D01*
G01D02*
X135150Y453929D01*
G01D02*
Y458350D01*
G01D02*
X135871Y459071D01*
G01D02*
Y490124D01*
G01X157232Y482872D02*
Y451086D01*
G01D02*
X159239Y449079D01*
G01X153100Y445683D02*
X154719Y447302D01*
G01D02*
Y490125D01*
G01X148426Y486254D02*
Y458562D01*
G01D02*
X145612Y455748D01*
G01D02*
Y447628D01*
G01D02*
X143883Y445899D01*
G01X182588Y432150D02*
X164684Y450054D01*
G01D02*
Y451776D01*
G01D02*
X163440Y453020D01*
G01D02*
X162618Y453842D01*
G01D02*
Y485374D01*
G01X139194Y445970D02*
Y447972D01*
G01D02*
X140445Y449223D01*
G01D02*
Y483055D01*
G01X151570Y490124D02*
X150020Y491674D01*
G01X143721Y485374D02*
X143021Y484674D01*
G01D02*
Y484221D01*
G01D02*
X141345Y482545D01*
G01X161019Y490124D02*
X159469Y491674D01*
G01X139000Y490103D02*
X140571Y491674D01*
G01X135871Y490124D02*
X137421Y491674D01*
G01X156319D02*
X157869Y490124D01*
G01D02*
Y483509D01*
G01D02*
X157232Y482872D01*
G01X154719Y490125D02*
X153170Y491674D01*
G01X150020Y488524D02*
Y487848D01*
G01D02*
X148426Y486254D01*
G01X140445Y483055D02*
X142121Y484731D01*
G01D02*
Y486924D01*
G01D02*
X143721Y488524D01*
G01X168499Y491136D02*
X163262Y496373D01*
G01D02*
X146226D01*
G01D02*
X143721Y493868D01*
G01D02*
Y491674D01*
G01X131764Y531067D02*
X133315Y532618D01*
G01D02*
X134272D01*
G01X165350Y681050D02*
X162100Y677800D01*
G01X142250Y682550D02*
X210800D01*
G01X167600Y247600D02*
X179353Y235847D01*
G01D02*
X269798D01*
G01X209084Y343084D02*
X175907D01*
G01D02*
X175883Y343108D01*
G01D02*
X175692D01*
G01D02*
X171870Y346930D01*
G01X165221Y331900D02*
X167687Y329434D01*
G01X167675Y334900D02*
X169791Y332784D01*
G01D02*
X212800D01*
G01X166457Y333400D02*
X169952Y329905D01*
G01D02*
X189365D01*
G01X208972Y340850D02*
X175600D01*
G01D02*
X171020Y345430D01*
G01X167713Y337098D02*
X170321Y334490D01*
G01D02*
X213216D01*
G01X178800Y353500D02*
X182457Y349843D01*
G01D02*
X194088D01*
G01D02*
X196529Y352284D01*
G01X180610Y355000D02*
X182969Y352641D01*
G01X173178Y348430D02*
X176674Y344934D01*
G01X185932Y359000D02*
X185970Y358962D01*
G01X177916Y351783D02*
X181356Y348343D01*
G01D02*
X195469D01*
G01D02*
X195940Y348814D01*
G01X165673Y369903D02*
X179381D01*
G01X177154Y349930D02*
X180300Y346784D01*
G01D02*
X205858D01*
G01X178531Y414373D02*
X182675Y410229D01*
G01D02*
X222951D01*
G01X222350Y411750D02*
X185424D01*
G01D02*
X178807Y418367D01*
G01X201791Y433934D02*
X197513Y429656D01*
G01X177678Y423300D02*
X187728Y413250D01*
G01D02*
X219750D01*
G01X198135Y428156D02*
X202412Y432433D01*
G01X201169Y435434D02*
X197885Y432150D01*
G01D02*
X182588D01*
G01X203033Y430932D02*
X198757Y426656D01*
G01X212767Y440563D02*
X197000D01*
G01D02*
X168499Y469064D01*
G01D02*
Y491136D01*
G01X172065Y507422D02*
Y507365D01*
G01D02*
X170515Y505815D01*
G01D02*
Y503629D01*
G01D02*
X171422Y502722D01*
G01D02*
X172658D01*
G01D02*
X173665Y501715D01*
G01D02*
Y500479D01*
G01D02*
X174572Y499572D01*
G01D02*
X191100D01*
G01D02*
X200328Y508800D01*
G01X215000Y510300D02*
X198000D01*
G01D02*
X192672Y504972D01*
G01D02*
X179065D01*
G01D02*
X178365Y504272D01*
G01X192199Y514400D02*
X186820Y509021D01*
G01D02*
X174621D01*
G01D02*
X173665Y508065D01*
G01D02*
Y505822D01*
G01D02*
X175216Y504271D01*
G01X172065Y504272D02*
X173022D01*
G01D02*
X174573Y502721D01*
G01D02*
X175859D01*
G01D02*
X176766Y503628D01*
G01D02*
Y504866D01*
G01D02*
X177772Y505872D01*
G01D02*
X188299D01*
G01D02*
X194927Y512500D01*
G01D02*
X215183D01*
G01X172065Y510571D02*
X173022D01*
G01D02*
X174572Y512121D01*
G01D02*
X175808D01*
G01D02*
X176800Y513113D01*
G01X165766Y542066D02*
X181926Y558226D01*
G01X172065Y513721D02*
X173666Y515322D01*
G01D02*
Y522526D01*
G01D02*
X173665Y522527D01*
G01D02*
Y523813D01*
G01D02*
X174572Y524720D01*
G01D02*
X230640D01*
G01X216233Y527900D02*
X173646D01*
G01D02*
X172065Y526319D01*
G01Y535768D02*
X173615Y537318D01*
G01D02*
X182318D01*
G01D02*
X196150Y551150D01*
G01X225517Y514400D02*
X192199D01*
G01X172065Y529469D02*
X172169D01*
G01D02*
X173768Y531068D01*
G01D02*
X182995D01*
G01D02*
X184527Y532600D01*
G01D02*
X218889D01*
G01X176800Y513113D02*
Y520648D01*
G01D02*
X177722Y521570D01*
G01D02*
X216653D01*
G01X178365Y529469D02*
X182669D01*
G01D02*
X184300Y531100D01*
G01D02*
X218267D01*
G01X181926Y558226D02*
X198146D01*
G01D02*
X201533Y561613D01*
G01X196150Y551150D02*
X209122D01*
G01X193001Y574708D02*
X194489Y573220D01*
G01D02*
X222500D01*
G01X200742Y563113D02*
X198675Y561046D01*
G01D02*
X191632D01*
G01D02*
X189500Y563178D01*
G01D02*
Y567700D01*
G01X199989Y592100D02*
X188178D01*
G01D02*
X186778Y590700D01*
G01D02*
X186700D01*
G01D02*
X181000Y585000D01*
G01X205000Y581500D02*
X181000D01*
G01X210178Y681050D02*
X165350D01*
G01X213088Y347088D02*
X209084Y343084D01*
G01X212800Y332784D02*
X214270Y331314D01*
G01D02*
X256285D01*
G01X351165Y340490D02*
X231010D01*
G01D02*
X228965Y342535D01*
G01D02*
X210657D01*
G01D02*
X208972Y340850D01*
G01X213216Y334490D02*
X214892Y332814D01*
G01D02*
X255663D01*
G01X205840Y377149D02*
X211222Y371767D01*
G01D02*
X236953D01*
G01X256012Y347088D02*
X213088D01*
G01X280660Y365100D02*
X231685D01*
G01D02*
X230335Y366450D01*
G01D02*
X207618D01*
G01D02*
X202315Y371753D01*
G01X267100Y362000D02*
X232400D01*
G01D02*
X230500Y363900D01*
G01D02*
X228800D01*
G01D02*
X228100Y364600D01*
G01X205858Y346784D02*
X208879Y349805D01*
G01D02*
X212536D01*
G01X295734Y383832D02*
X216369D01*
G01D02*
X211186Y378649D01*
G01X295112Y385332D02*
X215516D01*
G01D02*
X210333Y380149D01*
G01X222951Y410229D02*
X228022Y415300D01*
G01X233050Y416800D02*
X227400D01*
G01D02*
X222350Y411750D01*
G01X308732Y433932D02*
X204277D01*
G01D02*
X204276Y433933D01*
G01D02*
X203034D01*
G01D02*
X203033Y433934D01*
G01D02*
X201791D01*
G01X219750Y413250D02*
X226300Y419800D01*
G01D02*
X233433D01*
G01X202412Y432433D02*
X203654D01*
G01D02*
X203655Y432432D01*
G01D02*
X311132D01*
G01X205915Y422424D02*
X205413Y422926D01*
G01D02*
X204236D01*
G01D02*
X202006Y425156D01*
G01X228022Y415300D02*
X234167D01*
G01X293132Y435432D02*
X204899D01*
G01D02*
X204898Y435433D01*
G01D02*
X203656D01*
G01D02*
X203655Y435434D01*
G01D02*
X201169D01*
G01X311971Y430932D02*
X203033D01*
G01X256494Y436932D02*
X216398D01*
G01D02*
X212767Y440563D01*
G01X206700Y494000D02*
Y490400D01*
G01D02*
X210100Y487000D01*
G01D02*
X221477D01*
G01D02*
X227777Y493300D01*
G01D02*
X230696D01*
G01D02*
X232523Y495127D01*
G01X200328Y508800D02*
X214300D01*
G01D02*
X218800Y504300D01*
G01D02*
X222283D01*
G01D02*
X227662Y509679D01*
G01D02*
X240485D01*
G01X207026Y483956D02*
X209646Y481336D01*
G01D02*
X219673D01*
G01D02*
X220037Y481700D01*
G01D02*
X231500D01*
G01D02*
X234733Y484933D01*
G01X239864Y511180D02*
X227041D01*
G01D02*
X222161Y506300D01*
G01D02*
X219000D01*
G01D02*
X215000Y510300D01*
G01X203550Y484522D02*
X204328Y485300D01*
G01D02*
X205753D01*
G01D02*
X206259Y485806D01*
G01D02*
X207793D01*
G01D02*
X208299Y485300D01*
G01D02*
X222000D01*
G01D02*
X228500Y491800D01*
G01D02*
X231813D01*
G01D02*
X233290Y493277D01*
G01X238051Y496627D02*
X231901D01*
G01D02*
X230074Y494800D01*
G01D02*
X225500D01*
G01D02*
X222500Y491800D01*
G01D02*
X211750D01*
G01D02*
X207700Y495850D01*
G01D02*
X205850D01*
G01D02*
X204212Y497488D01*
G01D02*
X201916D01*
G01D02*
X200400Y495972D01*
G01D02*
Y493100D01*
G01D02*
X200917Y492583D01*
G01D02*
Y490578D01*
G01X215183Y512500D02*
X217033Y510650D01*
G01D02*
X218567D01*
G01D02*
X219017Y511100D01*
G01D02*
X223601D01*
G01D02*
X225182Y512681D01*
G01D02*
X239243D01*
G01X238673Y498127D02*
X231279D01*
G01D02*
X229452Y496300D01*
G01D02*
X224794D01*
G01D02*
X224294Y495800D01*
G01D02*
X219300D01*
G01D02*
X219050Y495550D01*
G01D02*
X219033D01*
G01D02*
X217950Y494467D01*
G01D02*
Y494450D01*
G01D02*
X217400Y493900D01*
G01D02*
X211800D01*
G01D02*
X208041Y497659D01*
G01D02*
X207041D01*
G01D02*
X206700Y498000D01*
G01X240173Y499627D02*
X230657D01*
G01D02*
X228830Y497800D01*
G01D02*
X218017D01*
G01D02*
X217417Y498400D01*
G01D02*
X215783D01*
G01D02*
X215183Y497800D01*
G01D02*
X209600D01*
G01D02*
X207750Y499650D01*
G01D02*
X205733D01*
G01D02*
X205183Y499100D01*
G01D02*
X203600D01*
G01D02*
X203500Y499200D01*
G01X230640Y524720D02*
X230997Y525077D01*
G01D02*
X239139D01*
G01X285439Y535100D02*
X222755D01*
G01D02*
X220755Y537100D01*
G01D02*
X208100D01*
G01D02*
X206700Y538500D01*
G01X283076Y533600D02*
X222133D01*
G01D02*
X220133Y535600D01*
G01D02*
X206200D01*
G01D02*
X203300Y538500D01*
G01X245220Y527600D02*
X219645D01*
G01D02*
X219445Y527400D01*
G01D02*
X216733D01*
G01D02*
X216233Y527900D01*
G01X283250Y545050D02*
X219589D01*
G01D02*
X219039Y544500D01*
G01D02*
X206700D01*
G01X266719Y519056D02*
X230173D01*
G01D02*
X225517Y514400D01*
G01X218889Y532600D02*
X220889Y530600D01*
G01D02*
X266344D01*
G01X282339Y543150D02*
X219811D01*
G01D02*
X219311Y542650D01*
G01D02*
X202533D01*
G01D02*
X200683Y544500D01*
G01D02*
X199900D01*
G01X216653Y521570D02*
X216733Y521650D01*
G01D02*
X218267D01*
G01D02*
X218836Y521081D01*
G01D02*
X239321D01*
G01X218267Y531100D02*
X220267Y529100D01*
G01D02*
X265722D01*
G01X201533Y561613D02*
X206467D01*
G01D02*
X207605Y560475D01*
G01D02*
X217525D01*
G01D02*
X217918Y560082D01*
G01D02*
X218780D01*
G01X273100Y558500D02*
X229800D01*
G01X259883Y548500D02*
X206700D01*
G01X209122Y551150D02*
X211122Y553150D01*
G01D02*
X217050D01*
G01D02*
X219700Y550500D01*
G01X202300Y559763D02*
X204305Y557758D01*
G01D02*
X217625D01*
G01D02*
X221309Y554074D01*
G01D02*
X273926D01*
G01X269843Y564945D02*
X208921D01*
G01D02*
X207089Y563113D01*
G01D02*
X200742D01*
G01X233500Y592000D02*
X200089D01*
G01D02*
X199989Y592100D01*
G01X232878Y590500D02*
X214000D01*
G01D02*
X205000Y581500D01*
G01X210800Y682550D02*
X221650Y671700D01*
G01D02*
X312600D01*
G01X313222Y670200D02*
X221028D01*
G01D02*
X210178Y681050D01*
G01X279468Y136250D02*
X234250D01*
G01D02*
X233500Y137000D01*
G01X267979Y342500D02*
X260600D01*
G01D02*
X256012Y347088D01*
G01X256285Y331314D02*
X259641Y334670D01*
G01D02*
X273959D01*
G01X255663Y332814D02*
X259019Y336170D01*
G01D02*
X274581D01*
G01X236953Y371767D02*
X238004Y370716D01*
G01D02*
X282428D01*
G01X235750Y419500D02*
X233050Y416800D01*
G01X233433Y419800D02*
X234983Y421350D01*
G01D02*
X238095D01*
G01D02*
X238145Y421400D01*
G01D02*
X249421D01*
G01D02*
X249850Y420971D01*
G01D02*
Y420833D01*
G01D02*
X250933Y419750D01*
G01D02*
X315572D01*
G01X234167Y415300D02*
X238767Y419900D01*
G01D02*
X248661D01*
G01D02*
X250311Y418250D01*
G01D02*
X250449D01*
G01D02*
X250800Y417899D01*
G01D02*
X312357D01*
G01X266267Y437950D02*
X263667Y440550D01*
G01D02*
X260112D01*
G01D02*
X256494Y436932D01*
G01X232523Y495127D02*
X237429D01*
G01D02*
X237856Y494700D01*
G01D02*
X237940D01*
G01D02*
X239240Y493400D01*
G01D02*
X246500D01*
G01X240485Y509679D02*
X245362Y514556D01*
G01X234733Y484933D02*
Y491166D01*
G01D02*
X236737Y493170D01*
G01X244740Y516056D02*
X239864Y511180D01*
G01X242800Y495486D02*
X239276D01*
G01D02*
X238562Y496200D01*
G01D02*
X238478D01*
G01D02*
X238051Y496627D01*
G01X239243Y512681D02*
X244118Y517556D01*
G01X246800Y496800D02*
X246050Y497550D01*
G01D02*
X239633D01*
G01D02*
X239483Y497700D01*
G01D02*
X239100D01*
G01D02*
X238673Y498127D01*
G01X240450Y499400D02*
X240400D01*
G01D02*
X240173Y499627D01*
G01X245362Y514556D02*
X264560D01*
G01D02*
X267082Y512034D01*
G01X268813Y523887D02*
X248933D01*
G01D02*
X245220Y527600D01*
G01X268582Y512656D02*
X265182Y516056D01*
G01D02*
X244740D01*
G01X244118Y517556D02*
X265804D01*
G01D02*
X284331Y499029D01*
G01X266344Y530600D02*
X278544Y518400D01*
G01X265722Y529100D02*
X277922Y516900D01*
G01X270454Y575850D02*
X262950D01*
G01D02*
X257800Y581000D01*
G01X282409Y548050D02*
X260333D01*
G01D02*
X259883Y548500D01*
G01X269832Y574350D02*
X262328D01*
G01D02*
X257179Y579499D01*
G01D02*
X243879D01*
G01D02*
X232878Y590500D01*
G01X257800Y581000D02*
X244500D01*
G01D02*
X233500Y592000D01*
G01X262628Y744470D02*
X263358Y745200D01*
G01D02*
X293692D01*
G01X284440Y139580D02*
X283560Y138700D01*
G01D02*
X281918D01*
G01D02*
X279468Y136250D01*
G01X269798Y235847D02*
X270464Y235181D01*
G01D02*
X271998D01*
G01D02*
X272664Y235847D01*
G01D02*
X286747D01*
G01D02*
X302500Y251600D01*
G01X301982Y334501D02*
X295400Y327919D01*
G01D02*
Y325390D01*
G01X273959Y334670D02*
X286589Y322040D01*
G01D02*
X298540D01*
G01D02*
X301910Y325410D01*
G01X274581Y336170D02*
X287211Y323540D01*
G01D02*
X297918D01*
G01D02*
X301288Y326910D01*
G01X334128Y336001D02*
X297371D01*
G01D02*
X288172Y326802D01*
G01D02*
X287200D01*
G01X282428Y370716D02*
X283933Y372221D01*
G01D02*
X304523D01*
G01X301320Y362500D02*
X298907Y364913D01*
G01D02*
X292630D01*
G01D02*
X291107Y363390D01*
G01D02*
X282370D01*
G01D02*
X280660Y365100D01*
G01X267300Y362200D02*
X267100Y362000D01*
G01X302302Y390400D02*
X295734Y383832D01*
G01X301680Y391900D02*
X295112Y385332D01*
G01X293800Y436100D02*
X293132Y435432D01*
G01X310450Y437950D02*
X266267D01*
G01X267082Y512034D02*
Y508633D01*
G01D02*
X267083Y508632D01*
G01D02*
Y505732D01*
G01D02*
X267082Y505731D01*
G01D02*
Y504263D01*
G01D02*
X277845Y493500D01*
G01D02*
X288200D01*
G01D02*
X300350Y481350D01*
G01X303800Y505100D02*
X293500Y515400D01*
G01X322036Y463198D02*
X298673Y486561D01*
G01D02*
X297261D01*
G01D02*
X288626Y495196D01*
G01D02*
X281865D01*
G01D02*
X268583Y508478D01*
G01D02*
Y509254D01*
G01D02*
X268582Y512656D01*
G01X322305Y474812D02*
X293068Y504049D01*
G01D02*
X281726D01*
G01D02*
X266719Y519056D01*
G01X284331Y499029D02*
Y497779D01*
G01D02*
X285414Y496696D01*
G01D02*
X289248D01*
G01D02*
X297372Y488572D01*
G01D02*
X303095D01*
G01X307750Y512789D02*
X285439Y535100D01*
G01X295876Y520800D02*
X283076Y533600D01*
G01X293500Y515400D02*
X277300D01*
G01D02*
X268813Y523887D01*
G01X314109Y516350D02*
X282409Y548050D01*
G01X303117Y529465D02*
X299900Y532682D01*
G01D02*
Y560900D01*
G01X313450Y514850D02*
X283250Y545050D01*
G01X278544Y518400D02*
X300017D01*
G01D02*
X306250Y512167D01*
G01X312139Y513350D02*
X282339Y543150D01*
G01X277922Y516900D02*
X298900D01*
G01D02*
X304400Y511400D01*
G01X296200Y566900D02*
X279404D01*
G01D02*
X270454Y575850D01*
G01X280200Y551400D02*
X273100Y558500D01*
G01X299900Y560900D02*
X295750Y565050D01*
G01D02*
X295433D01*
G01D02*
X295083Y565400D01*
G01D02*
X278782D01*
G01D02*
X269832Y574350D01*
G01X273926Y554074D02*
X278450Y549550D01*
G01D02*
X281750D01*
G01D02*
X283600Y551400D01*
G01X279994Y554794D02*
X269843Y564945D01*
G01X293692Y745200D02*
X294058Y744834D01*
G01D02*
X319966D01*
G01X302500Y207200D02*
Y243500D01*
G01D02*
X306900Y247900D01*
G01D02*
Y251000D01*
G01X356200Y238500D02*
X332760Y261940D01*
G01D02*
Y284782D01*
G01X313852Y310550D02*
X316799Y307603D01*
G01D02*
X321743D01*
G01D02*
X326946Y302400D01*
G01D02*
X330480D01*
G01D02*
X332350Y300529D01*
G01D02*
Y298833D01*
G01D02*
X333433Y297750D01*
G01D02*
X335129D01*
G01X372800Y252617D02*
X319314Y306103D01*
G01D02*
X311160D01*
G01D02*
X307425Y309838D01*
G01X332760Y284782D02*
X314439Y303103D01*
G01D02*
X307574D01*
G01D02*
X301667Y309010D01*
G01D02*
Y310544D01*
G01X334260Y285404D02*
X315061Y304603D01*
G01D02*
X308691D01*
G01D02*
X303517Y309777D01*
G01X311882Y310550D02*
X313852D01*
G01X345109Y322898D02*
X333506Y334501D01*
G01D02*
X301982D01*
G01X301910Y325410D02*
X319990D01*
G01D02*
X325502Y319898D01*
G01D02*
X343370D01*
G01X301667Y310544D02*
X305793Y314670D01*
G01D02*
X310485D01*
G01X301288Y326910D02*
X320612D01*
G01D02*
X326124Y321398D01*
G01D02*
X365819D01*
G01X341377Y315900D02*
X328800D01*
G01X304523Y372221D02*
X310158Y377856D01*
G01D02*
X349361D01*
G01X436678Y390400D02*
X302302D01*
G01X421256Y391900D02*
X301680D01*
G01X313500Y437400D02*
X312200D01*
G01D02*
X308732Y433932D01*
G01X315572Y419750D02*
X335413Y439591D01*
G01X311132Y432432D02*
X312700Y434000D01*
G01D02*
X313288D01*
G01D02*
X313294Y434006D01*
G01X312357Y417899D02*
X312857Y417399D01*
G01D02*
X316899D01*
G01D02*
X337591Y438091D01*
G01X313300Y429603D02*
X311971Y430932D01*
G01X313500Y441000D02*
X310450Y437950D01*
G01X301672Y481350D02*
X314300Y468722D01*
G01D02*
Y467400D01*
G01D02*
X321900Y459800D01*
G01X322305Y469991D02*
Y474812D01*
G01X303095Y488572D02*
X317200Y474467D01*
G01D02*
Y471659D01*
G01D02*
X322268Y466591D01*
G01X329014Y482503D02*
Y472022D01*
G01X300350Y481350D02*
X301672D01*
G01X333102Y485902D02*
Y486191D01*
G01D02*
X307750Y511543D01*
G01D02*
Y512789D01*
G01X330000Y501900D02*
Y504506D01*
G01D02*
X318156Y516350D01*
G01X327512Y509612D02*
X319274Y517850D01*
G01X327589Y504300D02*
X317039Y514850D01*
G01X306250Y512167D02*
Y505267D01*
G01D02*
X329014Y482503D01*
G01X335570Y491460D02*
X313680Y513350D01*
G01X318156Y516350D02*
X314109D01*
G01X319274Y517850D02*
X314731D01*
G01D02*
X313648Y518933D01*
G01D02*
X303117Y529465D01*
G01X317039Y514850D02*
X313450D01*
G01X313680Y513350D02*
X312139D01*
G01X312600Y671700D02*
X320000Y679100D01*
G01D02*
Y718200D01*
G01X321500Y692100D02*
Y678478D01*
G01D02*
X313222Y670200D01*
G01X332200Y732600D02*
Y684000D01*
G01D02*
X581000Y435200D01*
G01X323600Y717800D02*
Y694200D01*
G01D02*
X321500Y692100D01*
G01X319966Y744834D02*
X332200Y732600D01*
G01X367485Y130889D02*
X473715Y24659D01*
G01X473093Y23159D02*
X365985Y130267D01*
G01D02*
Y199594D01*
G01X471850Y20158D02*
X352950Y139058D01*
G01D02*
Y186450D01*
G01X472471Y21659D02*
X364485Y129645D01*
G01D02*
Y234115D01*
G01X374301Y205788D02*
X367485Y198972D01*
G01X365985Y199594D02*
X372800Y206409D01*
G01X352950Y186450D02*
X356200Y189700D01*
G01D02*
Y238500D01*
G01X364485Y234115D02*
X334260Y264340D01*
G01X340960Y291920D02*
X374300Y258580D01*
G01X334260Y264340D02*
Y285404D01*
G01X335129Y297750D02*
X338870Y294010D01*
G01D02*
X338999D01*
G01D02*
X340960Y292049D01*
G01D02*
Y291920D01*
G01X379100Y278177D02*
X341377Y315900D01*
G01X375600Y314112D02*
X366814Y322898D01*
G01D02*
X345109D01*
G01X387600Y320388D02*
X356953Y351036D01*
G01X368056Y328900D02*
X367096D01*
G01D02*
X354505Y341491D01*
G01D02*
Y356102D01*
G01X343370Y319898D02*
X347568Y315700D01*
G01D02*
X368900D01*
G01X368678Y327400D02*
X366474D01*
G01D02*
X352003Y341871D01*
G01D02*
Y358603D01*
G01X368057Y325899D02*
X365756D01*
G01D02*
X351165Y340490D01*
G01X360024Y351203D02*
X389100Y322127D01*
G01X365819Y321398D02*
X374100Y313117D01*
G01X377100Y314734D02*
X367436Y324398D01*
G01D02*
X367063D01*
G01D02*
X367062Y324399D01*
G01D02*
X364576D01*
G01D02*
X364575Y324398D01*
G01D02*
X345731D01*
G01D02*
X334128Y336001D01*
G01X349361Y377856D02*
X398100Y329117D01*
G01X390600Y322749D02*
X355872Y357477D01*
G01D02*
Y363965D01*
G01X356953Y351036D02*
Y353653D01*
G01X392100Y323371D02*
X358362Y357109D01*
G01D02*
Y361649D01*
G01X363270Y356940D02*
X363528D01*
G01D02*
X395100Y325368D01*
G01X393600Y323993D02*
X360820Y356773D01*
G01D02*
Y359299D01*
G01X359403Y351203D02*
X360024D01*
G01X335413Y439591D02*
X543309D01*
G01X337591Y438091D02*
X536509D01*
G01X334800Y685500D02*
X582400Y437900D01*
G01X334800Y712000D02*
Y685500D01*
G01X354300Y696000D02*
Y704500D01*
G01X474384Y29648D02*
X371485Y132547D01*
G01X367485Y198972D02*
Y130889D01*
G01X476416Y33649D02*
X375485Y134580D01*
G01D02*
Y191227D01*
G01X454187Y77243D02*
X390485Y140945D01*
G01D02*
Y185008D01*
G01X452943Y74243D02*
X387485Y139701D01*
G01D02*
Y186252D01*
G01X450456Y68243D02*
X381485Y137214D01*
G01D02*
Y188739D01*
G01X454809Y78743D02*
X391985Y141567D01*
G01D02*
Y184386D01*
G01X456675Y83243D02*
X396485Y143433D01*
G01X394985Y142811D02*
X456053Y81743D01*
G01X455431Y80243D02*
X393485Y142189D01*
G01X478428Y38149D02*
X379985Y136592D01*
G01D02*
Y189361D01*
G01X477806Y36649D02*
X378485Y135970D01*
G01D02*
Y189983D01*
G01X388985Y185630D02*
Y140323D01*
G01D02*
X453565Y75743D01*
G01X371485Y132547D02*
Y197314D01*
G01X477038Y35149D02*
X376985Y135202D01*
G01D02*
Y190605D01*
G01X396485Y143433D02*
Y175485D01*
G01X394985Y176107D02*
Y142811D01*
G01X393485Y142189D02*
Y176729D01*
G01X374300Y258580D02*
Y207031D01*
G01D02*
X374301Y207030D01*
G01D02*
Y205788D01*
G01X375485Y191227D02*
X385495Y201237D01*
G01D02*
Y294474D01*
G01X390485Y185008D02*
X400900Y195423D01*
G01D02*
Y282618D01*
G01X387485Y186252D02*
X397900Y196667D01*
G01D02*
Y281995D01*
G01X381485Y188739D02*
X391900Y199154D01*
G01D02*
Y281992D01*
G01X372800Y206409D02*
Y252617D01*
G01X391985Y184386D02*
X402400Y194801D01*
G01X396485Y175485D02*
X406900Y185900D01*
G01X405400Y186522D02*
X394985Y176107D01*
G01X393485Y176729D02*
X403900Y187144D01*
G01X379985Y189361D02*
X390400Y199776D01*
G01D02*
Y281991D01*
G01X378485Y189983D02*
X388900Y200398D01*
G01D02*
Y281990D01*
G01X399400Y281996D02*
Y196045D01*
G01D02*
X388985Y185630D01*
G01X383700Y294146D02*
Y203300D01*
G01D02*
X383600Y203200D01*
G01X371485Y197314D02*
X379100Y204929D01*
G01D02*
Y278177D01*
G01X376985Y190605D02*
X386995Y200615D01*
G01D02*
Y295096D01*
G01X385495Y294474D02*
X378701Y301267D01*
G01D02*
X378282Y301687D01*
G01D02*
X376987Y302983D01*
G01D02*
X376548Y303423D01*
G01D02*
Y303429D01*
G01D02*
X375600Y304381D01*
G01D02*
Y314112D01*
G01X400900Y282618D02*
X400899Y293486D01*
G01D02*
Y300290D01*
G01D02*
X390600Y310593D01*
G01X397900Y281995D02*
X397899Y293484D01*
G01D02*
Y299046D01*
G01D02*
X387600Y309349D01*
G01D02*
Y320388D01*
G01X391900Y281992D02*
X391899Y293481D01*
G01D02*
Y296559D01*
G01D02*
X386167Y302293D01*
G01D02*
X382550Y305911D01*
G01D02*
X381600Y306862D01*
G01D02*
Y316600D01*
G01X402399Y300912D02*
X392100Y311215D01*
G01X406899Y302778D02*
X396600Y313081D01*
G01X395100Y312459D02*
X405399Y302156D01*
G01X403899Y301534D02*
X393600Y311837D01*
G01X390400Y281991D02*
X390399Y293480D01*
G01D02*
Y295937D01*
G01D02*
X381887Y304450D01*
G01D02*
X381049Y305289D01*
G01D02*
X380100Y306241D01*
G01D02*
Y315978D01*
G01X388900Y281990D02*
X388899Y293479D01*
G01D02*
Y295315D01*
G01D02*
X380825Y303389D01*
G01D02*
X380406Y303809D01*
G01D02*
X379549Y304666D01*
G01D02*
Y304668D01*
G01D02*
X378600Y305621D01*
G01D02*
Y315356D01*
G01X389100Y322127D02*
Y309971D01*
G01D02*
X399399Y299668D01*
G01D02*
Y293485D01*
G01D02*
X399400Y281996D01*
G01X374100Y313117D02*
Y303761D01*
G01D02*
X375048Y302809D01*
G01D02*
Y302801D01*
G01D02*
X375340Y302509D01*
G01D02*
X375925Y301922D01*
G01D02*
X377220Y300626D01*
G01D02*
X377639Y300206D01*
G01D02*
X383700Y294146D01*
G01X386995Y295096D02*
X379763Y302328D01*
G01D02*
X379344Y302748D01*
G01D02*
X378049Y304044D01*
G01D02*
X378048Y304045D01*
G01D02*
Y304049D01*
G01D02*
X377100Y305001D01*
G01D02*
Y314734D01*
G01X398100Y329117D02*
Y313703D01*
G01D02*
X408399Y303401D01*
G01X390600Y310593D02*
Y322749D01*
G01X381600Y316600D02*
X369299Y328901D01*
G01D02*
X368057D01*
G01D02*
X368056Y328900D01*
G01X392100Y311215D02*
Y323371D01*
G01X396600Y313081D02*
Y328000D01*
G01D02*
X370700Y353900D01*
G01X395100Y325368D02*
Y312459D01*
G01X393600Y311837D02*
Y323993D01*
G01X380100Y315978D02*
X368678Y327400D01*
G01X378600Y315356D02*
X368057Y325899D01*
G01X402400Y194801D02*
Y282619D01*
G01X406900Y185900D02*
Y283243D01*
G01X405400Y283242D02*
Y186522D01*
G01X403900Y187144D02*
Y282620D01*
G01X408400Y283244D02*
Y219600D01*
G01D02*
X410900Y217100D01*
G01X408399Y303401D02*
Y294733D01*
G01D02*
X408400Y283244D01*
G01X402400Y282619D02*
X402399Y294108D01*
G01D02*
Y300912D01*
G01X406900Y283243D02*
X406899Y294732D01*
G01D02*
Y302778D01*
G01X405399Y302156D02*
Y294110D01*
G01D02*
X405400Y283242D01*
G01X403900Y282620D02*
X403899Y294109D01*
G01D02*
Y301534D01*
G01X442556Y413200D02*
X421256Y391900D01*
G01X480588Y39649D02*
X459550Y60687D01*
G01D02*
Y63067D01*
G01D02*
X454374Y68243D01*
G01D02*
X450456D01*
G01X481705Y41149D02*
X465127Y57727D01*
G01X470979Y77243D02*
X454187D01*
G01X469074Y74243D02*
X452943D01*
G01X468880Y78743D02*
X454809D01*
G01X473470Y83244D02*
X467017D01*
G01D02*
X467016Y83243D01*
G01D02*
X456675D01*
G01X456053Y81743D02*
X467638D01*
G01D02*
X467639Y81744D01*
G01D02*
X472846D01*
G01X472224Y80244D02*
X468261D01*
G01D02*
X468260Y80243D01*
G01D02*
X455431D01*
G01X453565Y75743D02*
X470127D01*
G01X457978Y411700D02*
X436678Y390400D01*
G01X505022Y411700D02*
X457978D01*
G01X505644Y413200D02*
X442556D01*
G01X477323Y24659D02*
X509917Y-7935D01*
G01X509295Y-9435D02*
X476701Y23159D01*
G01X508051Y-12435D02*
X475458Y20158D01*
G01X508673Y-10935D02*
X476079Y21659D01*
G01X473715Y24659D02*
X477323D01*
G01X519033Y4914D02*
X490282Y33649D01*
G01D02*
X476416D01*
G01X521521Y10914D02*
X492770Y39649D01*
G01D02*
X480588D01*
G01X476701Y23159D02*
X473093D01*
G01X475458Y20158D02*
X471850D01*
G01X520899Y9414D02*
X492148Y38149D01*
G01D02*
X478428D01*
G01X520277Y7914D02*
X491526Y36649D01*
G01D02*
X477806D01*
G01X476079Y21659D02*
X472471D01*
G01X522126Y12431D02*
X493392Y41149D01*
G01X521974Y-3683D02*
X488624Y29648D01*
G01D02*
X474384D01*
G01X519655Y6414D02*
X490904Y35149D01*
G01D02*
X477038D01*
G01X526825Y21416D02*
X470979Y77243D01*
G01X525351Y18416D02*
X486882Y56867D01*
G01D02*
X483246D01*
G01D02*
X480491Y59622D01*
G01D02*
Y62826D01*
G01D02*
X469074Y74243D01*
G01X527429Y22934D02*
X471601Y78744D01*
G01X529313Y27416D02*
X474002Y82712D01*
G01X473113Y81478D02*
X528691Y25916D01*
G01X528052Y24433D02*
X472224Y80244D01*
G01X470127Y75743D02*
X525970Y19919D01*
G01X493392Y41149D02*
X481705D01*
G01X471601Y78744D02*
X468882D01*
G01D02*
X468880Y78743D01*
G01X474002Y82712D02*
X473470Y83244D01*
G01X472846Y81744D02*
X473111Y81479D01*
G01D02*
X473113Y81478D01*
G01X469000Y784000D02*
X470000Y785000D01*
G01D02*
Y820500D01*
G01D02*
X474000Y824500D01*
G01D02*
X499500D01*
G01D02*
X500700Y825700D01*
G01D02*
Y828100D01*
G01X509917Y-7935D02*
X726993D01*
G01X695961Y4914D02*
X519033D01*
G01X744683Y-9435D02*
X509295D01*
G01X782911Y-12435D02*
X508051D01*
G01X781794Y-10935D02*
X508673D01*
G01X712784Y-3683D02*
X521974D01*
G01X696583Y6414D02*
X519655D01*
G01X716850Y21415D02*
X531571D01*
G01D02*
X531570Y21414D01*
G01D02*
X526827D01*
G01D02*
X526825Y21416D01*
G01X715606Y18415D02*
X532815D01*
G01D02*
X532814Y18414D01*
G01D02*
X525353D01*
G01D02*
X525351Y18416D01*
G01X698449Y10914D02*
X521521D01*
G01X701085Y22915D02*
X527448D01*
G01D02*
X527429Y22934D01*
G01X699219Y27415D02*
X534973D01*
G01D02*
X531862Y27416D01*
G01D02*
X529313D01*
G01X528691Y25916D02*
X528692Y25915D01*
G01D02*
X699841D01*
G01X700463Y24415D02*
X528070D01*
G01D02*
X528052Y24433D01*
G01X697827Y9414D02*
X520899D01*
G01X697205Y7914D02*
X520277D01*
G01X525970Y19919D02*
X525975Y19914D01*
G01D02*
X532192D01*
G01D02*
X532193Y19915D01*
G01D02*
X716228D01*
G01X699686Y12414D02*
X522144D01*
G01D02*
X522142Y12415D01*
G01D02*
X522126Y12431D01*
G01X530800Y123900D02*
X516100D01*
G01D02*
X510100Y129900D01*
G01D02*
Y140828D01*
G01D02*
X509369Y141559D01*
G01X532978Y371023D02*
X534501Y369500D01*
G01D02*
X561300D01*
G01X561912Y390762D02*
X525960D01*
G01D02*
X505022Y411700D01*
G01X528850Y394750D02*
X524094D01*
G01D02*
X505644Y413200D01*
G01X519906Y764900D02*
X522256D01*
G01D02*
X525156Y762000D01*
G01D02*
X539500D01*
G01X519748Y768297D02*
X519795Y768250D01*
G01D02*
X521028D01*
G01D02*
X525778Y763500D01*
G01D02*
X542500D01*
G01X515650Y764500D02*
X517898Y766748D01*
G01D02*
Y769198D01*
G01D02*
X518950Y770250D01*
G01D02*
X521150D01*
G01D02*
X526400Y765000D01*
G01D02*
X545000D01*
G01X542500Y821400D02*
X527700Y836200D01*
G01D02*
X527500D01*
G01X547173Y167987D02*
Y167973D01*
G01D02*
X553151Y173951D01*
G01D02*
X564187D01*
G01D02*
X573836Y183600D01*
G01X543309Y439591D02*
X567150Y415750D01*
G01X536509Y438091D02*
X560900Y413700D01*
G01X539500Y762000D02*
X540500Y761000D01*
G01Y781000D02*
X542500Y783000D01*
G01Y763500D02*
X544000Y762000D01*
G01D02*
Y761000D01*
G01X545000Y765000D02*
X547395Y762605D01*
G01D02*
Y761198D01*
G01X542500Y783000D02*
Y803383D01*
G01D02*
X544350Y805233D01*
G01D02*
Y806767D01*
G01D02*
X542500Y808617D01*
G01D02*
Y821400D01*
G01X573836Y183600D02*
X616671D01*
G01X582400Y437900D02*
X599600D01*
G01D02*
X615500Y422000D01*
G01X581000Y435200D02*
X597200D01*
G01D02*
X604400Y428000D01*
G01X616671Y183600D02*
X624211Y191140D01*
G01D02*
X680660D01*
G01X615500Y422000D02*
Y420100D01*
G01X604400Y428000D02*
Y421200D01*
G01X740040Y869D02*
X702494D01*
G01D02*
X702493Y868D01*
G01D02*
X700007D01*
G01D02*
X695961Y4914D01*
G01X724785Y3869D02*
X701250D01*
G01D02*
X697205Y7914D01*
G01X725407Y2369D02*
X701872D01*
G01D02*
X701871Y2368D01*
G01D02*
X700629D01*
G01D02*
X696583Y6414D01*
G01X709250Y8824D02*
X700539D01*
G01D02*
X698449Y10914D01*
G01X719775Y23849D02*
X702019D01*
G01D02*
X701085Y22915D01*
G01X740807Y29737D02*
X701541D01*
G01D02*
X699219Y27415D01*
G01X699841Y25915D02*
X702163Y28237D01*
G01D02*
X741429D01*
G01X742051Y26737D02*
X702785D01*
G01D02*
X700463Y24415D01*
G01X709872Y7324D02*
X701161D01*
G01D02*
X701160Y7323D01*
G01D02*
X699918D01*
G01D02*
X697827Y9414D01*
G01X708524Y10324D02*
X701776D01*
G01D02*
X699686Y12414D01*
G01X680660Y191140D02*
X690300Y181500D01*
G01D02*
X693000D01*
G01D02*
X693300Y181200D01*
G01X726993Y-7935D02*
X727613Y-7315D01*
G01D02*
X728395D01*
G01X741115Y8310D02*
X738605Y5800D01*
G01D02*
X737700D01*
G01D02*
X734350Y9150D01*
G01X739227Y4300D02*
X736500D01*
G01D02*
X733150Y7650D01*
G01X739849Y2800D02*
X735800D01*
G01D02*
X733175Y5425D01*
G01D02*
X726341D01*
G01D02*
X724785Y3869D01*
G01X713461Y-3006D02*
X712784Y-3683D01*
G01X729132Y3575D02*
X726613D01*
G01D02*
X725407Y2369D01*
G01X743295Y23737D02*
X735436D01*
G01D02*
X731848Y20149D01*
G01D02*
X718116D01*
G01D02*
X716850Y21415D01*
G01X740950Y17148D02*
X730604D01*
G01D02*
X730603Y17149D01*
G01D02*
X716872D01*
G01D02*
X715606Y18415D01*
G01X734350Y9150D02*
X714262D01*
G01D02*
X713308Y10104D01*
G01D02*
X710530D01*
G01D02*
X709250Y8824D01*
G01X742673Y25237D02*
X732937D01*
G01D02*
X730601Y22901D01*
G01D02*
X720723D01*
G01D02*
X719775Y23849D01*
G01X733150Y7650D02*
X713640D01*
G01D02*
X712686Y8604D01*
G01D02*
X711152D01*
G01D02*
X709872Y7324D01*
G01X716228Y19915D02*
X717494Y18649D01*
G01D02*
X731226D01*
G01D02*
X732469Y18648D01*
G01D02*
X740327D01*
G01X743437Y11148D02*
X728117D01*
G01D02*
X728116Y11149D01*
G01D02*
X716043D01*
G01D02*
X716042Y11148D01*
G01D02*
X714386D01*
G01D02*
X713930Y11604D01*
G01D02*
X709804D01*
G01D02*
X708524Y10324D01*
G01X774281Y3809D02*
X742980D01*
G01D02*
X740040Y869D01*
G01X776167Y-9333D02*
X747873D01*
G01D02*
X746329Y-7789D01*
G01D02*
X744683Y-9435D01*
G01X741736Y6809D02*
X739227Y4300D01*
G01X770948Y8690D02*
X767567Y5309D01*
G01D02*
X742358D01*
G01D02*
X739849Y2800D01*
G01X805528Y32700D02*
X763188D01*
G01D02*
X759188Y28700D01*
G01D02*
X753724D01*
G01D02*
X753721Y28697D01*
G01D02*
X748256D01*
G01D02*
X743295Y23737D01*
G01X807400Y26401D02*
X761133D01*
G01D02*
X760432Y25700D01*
G01D02*
X755500D01*
G01D02*
X755495Y25695D01*
G01D02*
X749499D01*
G01D02*
X744978Y21176D01*
G01D02*
X740950Y17148D01*
G01X775000Y12300D02*
X758372D01*
G01D02*
X755222Y9150D01*
G01D02*
X746867D01*
G01D02*
X746027Y8310D01*
G01D02*
X741115D01*
G01X806150Y34200D02*
X762566D01*
G01D02*
X758566Y30200D01*
G01D02*
X752919D01*
G01D02*
X752917Y30198D01*
G01D02*
X747635D01*
G01D02*
X742673Y25237D01*
G01X807881Y38835D02*
X760835D01*
G01D02*
X756700Y34700D01*
G01D02*
X745770D01*
G01D02*
X740807Y29737D01*
G01X741429Y28237D02*
X746393Y33200D01*
G01D02*
X757322D01*
G01D02*
X761457Y37335D01*
G01D02*
X807259D01*
G01X806772Y35700D02*
X761944D01*
G01D02*
X757944Y31700D01*
G01D02*
X751992D01*
G01D02*
X751991Y31699D01*
G01D02*
X747014D01*
G01D02*
X742051Y26737D01*
G01X801630Y10700D02*
X763717D01*
G01D02*
X759826Y6809D01*
G01D02*
X741736D01*
G01X772482Y8690D02*
X770948D01*
G01X740327Y18648D02*
X748878Y27196D01*
G01D02*
X754646D01*
G01D02*
X754650Y27200D01*
G01D02*
X759810D01*
G01D02*
X763810Y31200D01*
G01D02*
X804906D01*
G01X762300Y16200D02*
X760150D01*
G01D02*
X755099Y11149D01*
G01D02*
X743438D01*
G01D02*
X743437Y11148D01*
G01X810221Y-6045D02*
X796473Y7700D01*
G01X778172D02*
X774281Y3809D01*
G01X807733Y-12047D02*
X794836Y850D01*
G01D02*
X786350D01*
G01D02*
X776167Y-9333D01*
G01X790150Y-1400D02*
Y-2933D01*
G01D02*
X790258Y-3041D01*
G01D02*
Y-5088D01*
G01D02*
X782911Y-12435D01*
G01X815377Y-3047D02*
X801630Y10700D01*
G01X810842Y-4544D02*
X797095Y9200D01*
G01X788408Y-4321D02*
X781794Y-10935D01*
G01X796473Y7700D02*
X778172D01*
G01X823178Y15050D02*
X805528Y32700D01*
G01X815999Y-1547D02*
X799700Y14752D01*
G01D02*
Y18201D01*
G01D02*
X797901Y20000D01*
G01D02*
X782700D01*
G01D02*
X775000Y12300D01*
G01X823800Y16550D02*
X806150Y34200D01*
G01X797095Y9200D02*
X777550D01*
G01D02*
X775957Y7607D01*
G01D02*
X773565D01*
G01D02*
X772482Y8690D01*
G01X804906Y31200D02*
X822556Y13550D01*
G01X868766Y-6047D02*
X810224D01*
G01D02*
X810221Y-6045D01*
G01X866900Y-1547D02*
X815999D01*
G01X950670Y-12047D02*
X807733D01*
G01X867522Y-3047D02*
X815377D01*
G01X868144Y-4547D02*
X810845D01*
G01D02*
X810842Y-4544D01*
G01X880249Y15050D02*
X823178D01*
G01X881493Y12050D02*
X821751D01*
G01D02*
X807400Y26401D01*
G01X879627Y16550D02*
X823800D01*
G01X853711Y29120D02*
X817596D01*
G01D02*
X807881Y38835D01*
G01X807259Y37335D02*
X816974Y27620D01*
G01D02*
X850049D01*
G01X849818Y22758D02*
X822826D01*
G01D02*
X822644Y22940D01*
G01D02*
X819532D01*
G01D02*
X806772Y35700D01*
G01X822556Y13550D02*
X880871D01*
G01X841350Y740350D02*
X837000Y736000D01*
G01D02*
Y735500D01*
G01X878963Y4150D02*
X868766Y-6047D01*
G01X878447Y10000D02*
X866900Y-1547D01*
G01X879069Y8500D02*
X867522Y-3047D01*
G01X879691Y7000D02*
X868144Y-4547D01*
G01X863300Y23575D02*
X859256D01*
G01D02*
X853711Y29120D01*
G01X850049Y27620D02*
X856102Y21567D01*
G01D02*
Y20781D01*
G01D02*
X857333Y19550D01*
G01D02*
X866496D01*
G01D02*
X869211Y22265D01*
G01D02*
X875649D01*
G01X875027Y20765D02*
X869833D01*
G01D02*
X867118Y18050D01*
G01D02*
X854385D01*
G01D02*
X852402Y20033D01*
G01D02*
Y20174D01*
G01D02*
X849818Y22758D01*
G01X846702Y117371D02*
X847071D01*
G01D02*
X854746Y125046D01*
G01D02*
X871893D01*
G01D02*
X873250Y126403D01*
G01X854400Y117500D02*
X855000D01*
G01D02*
X859970Y122470D01*
G01D02*
X872092D01*
G01X868200Y116000D02*
X869000D01*
G01D02*
X871358Y113642D01*
G01D02*
X901732D01*
G01X861300Y117800D02*
X898016D01*
G01X877000Y745000D02*
X867500Y735500D01*
G01D02*
X848000D01*
G01X869406Y745531D02*
X862725Y738850D01*
G01D02*
X843850D01*
G01D02*
X840500Y735500D01*
G01X873367Y745335D02*
Y745559D01*
G01D02*
X865158Y737350D01*
G01D02*
X847233D01*
G01D02*
X845383Y735500D01*
G01D02*
X844000D01*
G01X865406Y745598D02*
X860158Y740350D01*
G01D02*
X841350D01*
G01X916083Y2505D02*
X897400D01*
G01D02*
X895755Y4150D01*
G01D02*
X878963D01*
G01X919354Y24528D02*
X889727D01*
G01D02*
X880249Y15050D01*
G01X918110Y21528D02*
X890971D01*
G01D02*
X881493Y12050D01*
G01X917488Y20028D02*
X891593D01*
G01D02*
X881565Y10000D01*
G01D02*
X878447D01*
G01X919976Y26028D02*
X889105D01*
G01D02*
X879627Y16550D01*
G01X875649Y22265D02*
X876164Y21750D01*
G01D02*
X880583D01*
G01D02*
X887861Y29028D01*
G01D02*
X921220D01*
G01X920598Y27528D02*
X888483D01*
G01D02*
X881205Y20250D01*
G01D02*
X875542D01*
G01D02*
X875027Y20765D01*
G01X916866Y18528D02*
X893028D01*
G01D02*
X883000Y8500D01*
G01D02*
X879069D01*
G01X916236Y17028D02*
X893650D01*
G01D02*
X883622Y7000D01*
G01D02*
X879691D01*
G01X880871Y13550D02*
X890349Y23028D01*
G01D02*
X918732D01*
G01X907400Y46700D02*
X889100D01*
G01D02*
X883800Y41400D01*
G01X901732Y113642D02*
X903800Y115710D01*
G01D02*
Y124173D01*
G01D02*
X905243Y125616D01*
G01D02*
X905832D01*
G01D02*
X907506Y127290D01*
G01X898016Y117800D02*
X900369Y120153D01*
G01D02*
Y124679D01*
G01D02*
X901306Y125616D01*
G01D02*
X901895D01*
G01D02*
X904306Y128027D01*
G01D02*
Y128616D01*
G01D02*
X905243Y129553D01*
G01D02*
X905832D01*
G01D02*
X907506Y131227D01*
G01Y152238D02*
X906244Y153500D01*
G01D02*
X903981D01*
G01D02*
X901969Y155512D01*
G01X881720Y807390D02*
X905960D01*
G01D02*
X906450Y806900D01*
G01X876470Y808710D02*
X877200Y809440D01*
G01D02*
X905536D01*
G01D02*
X906396Y810300D01*
G01X874570Y811820D02*
X904225D01*
G01D02*
X906092Y813687D01*
G01X919486Y5908D02*
X916083Y2505D01*
G01X935236Y5908D02*
X938486Y9158D01*
G01X941209Y23555D02*
X920327D01*
G01D02*
X919354Y24528D01*
G01X958954Y21700D02*
X934881Y45773D01*
G01X943111Y13778D02*
X936334Y20555D01*
G01D02*
X919083D01*
G01D02*
X918110Y21528D01*
G01X938486Y9158D02*
Y15125D01*
G01D02*
X934556Y19055D01*
G01D02*
X918461D01*
G01D02*
X917488Y20028D01*
G01X944306Y25055D02*
X920949D01*
G01D02*
X919976Y26028D01*
G01X921220Y29028D02*
X922193Y28055D01*
G01D02*
X949176D01*
G01X946079Y26555D02*
X921571D01*
G01D02*
X920598Y27528D01*
G01X935236Y13778D02*
X931459Y17555D01*
G01D02*
X917839D01*
G01D02*
X916866Y18528D01*
G01X919486Y13778D02*
X916236Y17028D01*
G01X918732Y23028D02*
X919705Y22055D01*
G01D02*
X939431D01*
G01D02*
X946361Y15125D01*
G01X934881Y45773D02*
Y57322D01*
G01X959838Y24400D02*
X939064Y45174D01*
G01D02*
Y58104D01*
G01X961353Y66000D02*
X935817D01*
G01D02*
X928250Y58433D01*
G01D02*
Y58250D01*
G01D02*
X924900Y54900D01*
G01D02*
X915600D01*
G01D02*
X907400Y46700D01*
G01X907506Y127290D02*
Y127879D01*
G01D02*
X909180Y129553D01*
G01D02*
X909769D01*
G01D02*
X911900Y131684D01*
G01D02*
Y141821D01*
G01X907506Y131227D02*
Y152238D01*
G01X911900Y141821D02*
X913780Y143701D01*
G01X974605Y11888D02*
X950670Y-12047D01*
G01X950986Y5908D02*
X954236Y9158D01*
G01X962106D02*
X958856Y5908D01*
G01X946361Y9158D02*
X943111Y5908D01*
G01X950986Y13778D02*
X941209Y23555D01*
G01X963700Y21700D02*
X958954D01*
G01X970064Y18764D02*
X964428Y24400D01*
G01D02*
X959838D01*
G01X1014545Y11888D02*
X974605D01*
G01X954236Y9158D02*
Y15125D01*
G01D02*
X944306Y25055D01*
G01X986658Y30811D02*
X963710D01*
G01D02*
X959877Y26978D01*
G01X949176Y28055D02*
X962106Y15125D01*
G01D02*
Y9158D01*
G01X958856Y13778D02*
X946079Y26555D01*
G01X946361Y15125D02*
Y9158D01*
G01X975162Y53584D02*
X970448Y58298D01*
G01D02*
X968115D01*
G01D02*
X964105Y62308D01*
G01X986304Y32312D02*
X972519Y46097D01*
G01D02*
Y52872D01*
G01D02*
X970750Y54641D01*
G01D02*
Y55045D01*
G01D02*
X968997Y56798D01*
G01D02*
X966998D01*
G01D02*
X963140Y60656D01*
G01D02*
X960306D01*
G01D02*
X959855Y61107D01*
G01X977500Y54867D02*
X972250Y60117D01*
G01D02*
Y61983D01*
G01D02*
X970933Y63300D01*
G01D02*
X969067D01*
G01D02*
X968961Y63194D01*
G01D02*
X965836D01*
G01D02*
X964872Y64158D01*
G01D02*
X963338D01*
G01D02*
X963266Y64086D01*
G01D02*
X961353Y66000D01*
G01X1013464Y21759D02*
X995710D01*
G01D02*
X986658Y30811D01*
G01X1013323Y25862D02*
X995851D01*
G01D02*
X987901Y33812D01*
G01D02*
X987050D01*
G01D02*
X975162Y45700D01*
G01X1013629Y24046D02*
X995545D01*
G01D02*
X987279Y32312D01*
G01D02*
X986304D01*
G01X1014276Y37111D02*
X986578D01*
G01D02*
X977500Y46189D01*
G01X975162Y45700D02*
Y53584D01*
G01X977500Y46189D02*
Y54867D01*
G01X1002192Y113642D02*
X1013358D01*
G01X1001669Y114542D02*
X1015358D01*
G01X1013027Y105700D02*
X1007027Y111700D01*
G01D02*
X997500D01*
G01D02*
X995350Y113850D01*
G01X1013319Y106681D02*
X1007258Y112742D01*
G01D02*
X998174D01*
G01D02*
X996916Y114000D01*
G01X1070520Y-1900D02*
X1028333D01*
G01D02*
X1014545Y11888D01*
G01X1047869Y19131D02*
X1040906D01*
G01D02*
Y19150D01*
G01D02*
X1039404D01*
G01D02*
X1034879Y23675D01*
G01D02*
X1015380D01*
G01D02*
X1013464Y21759D01*
G01X1049676Y22151D02*
X1040798D01*
G01D02*
X1036273Y26676D01*
G01D02*
X1035701D01*
G01D02*
X1035700Y26675D01*
G01D02*
X1014136D01*
G01D02*
X1013323Y25862D01*
G01X1049055Y20650D02*
X1040026D01*
G01D02*
X1035501Y25175D01*
G01D02*
X1014758D01*
G01D02*
X1013629Y24046D01*
G01X1030139Y30209D02*
X1027848Y32500D01*
G01D02*
X1018887D01*
G01D02*
X1014276Y37111D01*
G01X1033617Y108500D02*
X1030298Y105181D01*
G01D02*
X1027406D01*
G01D02*
X1026887Y105700D01*
G01D02*
X1013027D01*
G01X1030883Y108438D02*
X1029126Y106681D01*
G01D02*
X1013319D01*
G01X1013358Y113642D02*
X1016000Y111000D01*
G01D02*
Y109000D01*
G01D02*
X1015948Y108948D01*
G01D02*
Y108500D01*
G01X1015358Y114542D02*
X1019900Y110000D01*
G01D02*
Y108500D01*
G01X1034500D02*
X1033617D01*
G01X1018200Y116800D02*
X1024000Y111000D01*
G01D02*
Y108500D01*
G01X1022398Y115360D02*
X1027483Y110275D01*
G01D02*
Y108431D01*
G01X1078851Y-10230D02*
X1072021Y-3400D01*
G01D02*
X1070520Y-1900D01*
G01X1076314Y-10235D02*
X1070279Y-4200D01*
G01D02*
X1069200D01*
G01X1052600Y14400D02*
X1047869Y19131D01*
G01X1076970Y30411D02*
X1075661Y29102D01*
G01D02*
X1075099D01*
G01D02*
X1064384Y18387D01*
G01D02*
Y17583D01*
G01D02*
X1061669Y14868D01*
G01D02*
X1056959D01*
G01D02*
X1049676Y22151D01*
G01X1082974Y14467D02*
X1074961Y22480D01*
G01D02*
X1070599D01*
G01D02*
X1065884Y17765D01*
G01D02*
Y14921D01*
G01D02*
X1064331Y13368D01*
G01D02*
X1056337D01*
G01D02*
X1049055Y20650D01*
G01X1275139Y-10230D02*
X1078851D01*
G01X1284809Y-11751D02*
X1078251D01*
G01D02*
X1078235Y-11735D01*
G01D02*
X1078234D01*
G01D02*
X1076733Y-10235D01*
G01D02*
X1076314D01*
G01X1143000Y242000D02*
X1158000Y257000D01*
G01X1161000Y252000D02*
X1151000Y242000D01*
G01X1147000D02*
X1159500Y254500D01*
G01X1158000Y257000D02*
Y284444D01*
G01X1161000Y283200D02*
Y252000D01*
G01X1159500Y254500D02*
Y283822D01*
G01X1158000Y284444D02*
X1171200Y297644D01*
G01D02*
Y341407D01*
G01X1174201Y337201D02*
Y296401D01*
G01D02*
X1161000Y283200D01*
G01X1159500Y283822D02*
X1172700Y297022D01*
G01D02*
Y340322D01*
G01X1171200Y341407D02*
X1217793Y388000D01*
G01X1219000Y382000D02*
X1174201Y337201D01*
G01X1172700Y340322D02*
X1218878Y386500D01*
G01X1217793Y388000D02*
X1264293D01*
G01X1273503Y382000D02*
X1219000D01*
G01X1218878Y386500D02*
X1264915D01*
G01X1312500Y27131D02*
X1275139Y-10230D01*
G01X1264293Y388000D02*
X1266143Y389850D01*
G01D02*
X1286150D01*
G01X1282000Y386500D02*
X1278003D01*
G01D02*
X1273503Y382000D01*
G01X1264915Y386500D02*
X1266765Y388350D01*
G01D02*
X1282767D01*
G01X1314000Y17440D02*
X1284809Y-11751D01*
G01X1361757Y342000D02*
X1297050D01*
G01D02*
X1293280Y345770D01*
G01X1282740Y350010D02*
X1290750Y342000D01*
G01D02*
X1291878D01*
G01D02*
X1293378Y340500D01*
G01D02*
X1362379D01*
G01X1361135Y343500D02*
X1299000D01*
G01D02*
X1292188Y350312D01*
G01X1360513Y345000D02*
X1301500D01*
G01D02*
X1299000Y347500D01*
G01X1292188Y350312D02*
X1290372D01*
G01D02*
X1289960Y349900D01*
G01X1286150Y389850D02*
X1289500Y386500D01*
G01X1282767Y388350D02*
X1283850Y387267D01*
G01D02*
Y384110D01*
G01D02*
X1282740Y383000D01*
G01X1312500Y148974D02*
Y27131D01*
G01X1314001Y145411D02*
X1314000Y17440D01*
G01X1339471Y139268D02*
Y142571D01*
G01X1317400Y143620D02*
X1332582D01*
G01D02*
X1341730Y152768D01*
G01D02*
X1349819D01*
G01X1350920Y169407D02*
X1345943Y164430D01*
G01D02*
X1338911D01*
G01D02*
X1328312Y153831D01*
G01D02*
X1317358D01*
G01D02*
X1314160Y150633D01*
G01D02*
X1312500Y148974D01*
G01X1339471Y142571D02*
X1346668Y149768D01*
G01X1349197Y154268D02*
X1340663D01*
G01D02*
X1331993Y145598D01*
G01D02*
X1318202D01*
G01D02*
X1316590Y147210D01*
G01X1348575Y155768D02*
X1340041D01*
G01D02*
X1336604Y152331D01*
G01D02*
X1319094D01*
G01D02*
X1314001Y147238D01*
G01D02*
Y145411D01*
G01X1340130Y145980D02*
X1345418Y151268D01*
G01D02*
X1350441D01*
G01X1322000Y276500D02*
X1326050Y280550D01*
G01D02*
X1353595D01*
G01X1336388Y685055D02*
X1331000Y679667D01*
G01D02*
Y662000D01*
G01X1348500Y672000D02*
X1336000D01*
G01D02*
X1334128Y673872D01*
G01D02*
Y674000D01*
G01X1336795Y685141D02*
X1336709Y685055D01*
G01D02*
X1336388D01*
G01X1349819Y152768D02*
X1361898Y164847D01*
G01D02*
X1380184D01*
G01X1359128Y167226D02*
X1356865Y169489D01*
G01D02*
X1354391D01*
G01D02*
X1354308Y169407D01*
G01D02*
X1350920D01*
G01X1346668Y149768D02*
X1351063D01*
G01D02*
X1363142Y161847D01*
G01D02*
X1380184D01*
G01X1383823Y170608D02*
X1379562Y166347D01*
G01D02*
X1361276D01*
G01D02*
X1349197Y154268D01*
G01X1354971Y167446D02*
Y166951D01*
G01D02*
X1354972Y166950D01*
G01D02*
Y162165D01*
G01D02*
X1348575Y155768D01*
G01X1350441Y151268D02*
X1362520Y163347D01*
G01D02*
X1380806D01*
G01X1353595Y280550D02*
X1353645Y280500D01*
G01D02*
X1364000D01*
G01X1387500Y317501D02*
X1363000Y342001D01*
G01D02*
X1361757Y342000D01*
G01X1390546Y318699D02*
X1364243Y345002D01*
G01X1362379Y340500D02*
X1385688Y317191D01*
G01X1389046Y318077D02*
X1363621Y343502D01*
G01D02*
X1362378Y343501D01*
G01D02*
X1361136D01*
G01D02*
X1361135Y343500D01*
G01X1364243Y345002D02*
X1361757D01*
G01D02*
X1361756Y345001D01*
G01D02*
X1360514D01*
G01D02*
X1360513Y345000D01*
G01X1351500Y675000D02*
X1348500Y672000D01*
G01X1380184Y164847D02*
X1385323Y169986D01*
G01D02*
Y175009D01*
G01D02*
X1387500Y177186D01*
G01X1380184Y161847D02*
X1380185Y161846D01*
G01D02*
X1381427D01*
G01D02*
X1390546Y170965D01*
G01D02*
Y318699D01*
G01X1383823Y175790D02*
Y170608D01*
G01X1380806Y163347D02*
X1389046Y171587D01*
G01D02*
Y318077D01*
G01X1387500Y177186D02*
Y317501D01*
G01X1385688Y317191D02*
Y184240D01*
G01D02*
X1383536Y182088D01*
G01D02*
Y176077D01*
G01D02*
X1383823Y175790D01*
G54D12*
G01X-27072Y-83981D02*
Y-101481D01*
G01X-32094Y-83981D02*
X-22050D01*
G01X-13284Y-101481D02*
Y-83981D01*
G01Y-92439D02*
X-12192Y-90981D01*
X-11100Y-90106D01*
X-9354Y-89815D01*
X-8044Y-90106D01*
X-6515Y-91273D01*
X-5860Y-93023D01*
Y-101481D01*
G01X7928Y-89815D02*
Y-101481D01*
G01Y-85148D02*
X7491Y-84856D01*
Y-84273D01*
X7928Y-83981D01*
X8365Y-84273D01*
Y-84856D01*
X7928Y-85148D01*
G01X22153Y-99440D02*
X23245Y-100606D01*
X24773Y-101481D01*
X26083D01*
X27393Y-100898D01*
X28266Y-100023D01*
X28703Y-98857D01*
X28485Y-97106D01*
X27611Y-96231D01*
X23681Y-94481D01*
X22808Y-92439D01*
X23245Y-90981D01*
X24118Y-90106D01*
X25428Y-89815D01*
X26738Y-90106D01*
X28048Y-90981D01*
G01X57371Y-105856D02*
X58900Y-107023D01*
X60646Y-107314D01*
X62174Y-107023D01*
X63485Y-105565D01*
X64358Y-103523D01*
Y-89815D01*
G01Y-92148D02*
X63485Y-90981D01*
X62174Y-90106D01*
X60646Y-89815D01*
X58900Y-90398D01*
X57808Y-91564D01*
X56934Y-93606D01*
X56498Y-95648D01*
X56716Y-97398D01*
X57590Y-99440D01*
X58900Y-100898D01*
X60646Y-101481D01*
X61956Y-101189D01*
X63485Y-100023D01*
X64358Y-98857D01*
G01X74653Y-93606D02*
X81640D01*
X80985Y-91564D01*
X79893Y-90398D01*
X78365Y-89815D01*
X76836Y-90106D01*
X75526Y-90981D01*
X74653Y-93023D01*
X74216Y-94773D01*
Y-96523D01*
X74653Y-98273D01*
X75745Y-100023D01*
X77055Y-101189D01*
X78583Y-101481D01*
X80111Y-100898D01*
X81640Y-99148D01*
G01X92371Y-101481D02*
Y-89815D01*
G01Y-92148D02*
X93463Y-90981D01*
X94555Y-90106D01*
X96083Y-89815D01*
X97174Y-90106D01*
X98485Y-90981D01*
G01X108998Y-101481D02*
Y-83981D01*
G01Y-92731D02*
X110090Y-90981D01*
X111400Y-90106D01*
X112710Y-89815D01*
X114674Y-90398D01*
X115985Y-91564D01*
X116858Y-93606D01*
Y-95939D01*
X116421Y-98273D01*
X115548Y-100023D01*
X114020Y-101189D01*
X112710Y-101481D01*
X111400Y-101189D01*
X110090Y-100315D01*
X108998Y-98857D01*
G01X127153Y-93606D02*
X134140D01*
X133485Y-91564D01*
X132393Y-90398D01*
X130865Y-89815D01*
X129336Y-90106D01*
X128026Y-90981D01*
X127153Y-93023D01*
X126716Y-94773D01*
Y-96523D01*
X127153Y-98273D01*
X128245Y-100023D01*
X129555Y-101189D01*
X131083Y-101481D01*
X132611Y-100898D01*
X134140Y-99148D01*
G01X144871Y-101481D02*
Y-89815D01*
G01Y-92148D02*
X145963Y-90981D01*
X147055Y-90106D01*
X148583Y-89815D01*
X149674Y-90106D01*
X150985Y-90981D01*
G01X182928Y-89815D02*
Y-101481D01*
G01Y-85148D02*
X182491Y-84856D01*
Y-84273D01*
X182928Y-83981D01*
X183365Y-84273D01*
Y-84856D01*
X182928Y-85148D01*
G01X197153Y-99440D02*
X198245Y-100606D01*
X199773Y-101481D01*
X201083D01*
X202393Y-100898D01*
X203266Y-100023D01*
X203703Y-98857D01*
X203485Y-97106D01*
X202611Y-96231D01*
X198681Y-94481D01*
X197808Y-92439D01*
X198245Y-90981D01*
X199118Y-90106D01*
X200428Y-89815D01*
X201738Y-90106D01*
X203048Y-90981D01*
G01X231934Y-105856D02*
X233463Y-107023D01*
X234773Y-107314D01*
X236520Y-106731D01*
X237830Y-105273D01*
X238485Y-102647D01*
Y-89815D01*
G01Y-85148D02*
X238048Y-84856D01*
Y-84273D01*
X238485Y-83981D01*
X238921Y-84273D01*
Y-84856D01*
X238485Y-85148D01*
G01X249216Y-89815D02*
Y-97981D01*
X250090Y-100023D01*
X251400Y-101189D01*
X252928Y-101481D01*
X254456Y-101189D01*
X255766Y-100023D01*
X256640Y-97981D01*
G01Y-101481D02*
Y-89815D01*
G01X267153Y-99440D02*
X268245Y-100606D01*
X269773Y-101481D01*
X271083D01*
X272393Y-100898D01*
X273266Y-100023D01*
X273703Y-98857D01*
X273485Y-97106D01*
X272611Y-96231D01*
X268681Y-94481D01*
X267808Y-92439D01*
X268245Y-90981D01*
X269118Y-90106D01*
X270428Y-89815D01*
X271738Y-90106D01*
X273048Y-90981D01*
G01X287928Y-83981D02*
Y-101481D01*
G01X284871Y-89815D02*
X290985D01*
G01X321618Y-101481D02*
Y-86606D01*
X322055Y-85148D01*
X322928Y-84273D01*
X324238Y-83981D01*
X325548Y-84564D01*
X326203Y-86023D01*
G01X323583Y-90981D02*
X319216D01*
G01X340428Y-101481D02*
X339118Y-101189D01*
X337808Y-100023D01*
X336934Y-97981D01*
X336498Y-95648D01*
X336934Y-93314D01*
X337808Y-91273D01*
X339118Y-90106D01*
X340428Y-89815D01*
X341738Y-90106D01*
X343048Y-91273D01*
X343921Y-93314D01*
X344140Y-95648D01*
X343921Y-97981D01*
X343048Y-100023D01*
X341738Y-101189D01*
X340428Y-101481D01*
G01X354871D02*
Y-89815D01*
G01Y-92148D02*
X355963Y-90981D01*
X357055Y-90106D01*
X358583Y-89815D01*
X359674Y-90106D01*
X360985Y-90981D01*
G01X388343Y-106731D02*
X389653Y-107314D01*
X391400Y-106731D01*
X392491Y-105565D01*
X393365Y-104106D01*
X394674Y-99440D01*
X397513Y-89815D01*
G01X390526D02*
X394674Y-99440D01*
G01X410428Y-101481D02*
X409118Y-101189D01*
X407808Y-100023D01*
X406934Y-97981D01*
X406498Y-95648D01*
X406934Y-93314D01*
X407808Y-91273D01*
X409118Y-90106D01*
X410428Y-89815D01*
X411738Y-90106D01*
X413048Y-91273D01*
X413921Y-93314D01*
X414140Y-95648D01*
X413921Y-97981D01*
X413048Y-100023D01*
X411738Y-101189D01*
X410428Y-101481D01*
G01X424216Y-89815D02*
Y-97981D01*
X425090Y-100023D01*
X426400Y-101189D01*
X427928Y-101481D01*
X429456Y-101189D01*
X430766Y-100023D01*
X431640Y-97981D01*
G01Y-101481D02*
Y-89815D01*
G01X442371Y-101481D02*
Y-89815D01*
G01Y-92148D02*
X443463Y-90981D01*
X444555Y-90106D01*
X446083Y-89815D01*
X447174Y-90106D01*
X448485Y-90981D01*
G01X477371Y-101481D02*
Y-89815D01*
G01Y-92148D02*
X478463Y-90981D01*
X479555Y-90106D01*
X481083Y-89815D01*
X482174Y-90106D01*
X483485Y-90981D01*
G01X494653Y-93606D02*
X501640D01*
X500985Y-91564D01*
X499893Y-90398D01*
X498365Y-89815D01*
X496836Y-90106D01*
X495526Y-90981D01*
X494653Y-93023D01*
X494216Y-94773D01*
Y-96523D01*
X494653Y-98273D01*
X495745Y-100023D01*
X497055Y-101189D01*
X498583Y-101481D01*
X500111Y-100898D01*
X501640Y-99148D01*
G01X514118Y-101481D02*
Y-86606D01*
X514555Y-85148D01*
X515428Y-84273D01*
X516738Y-83981D01*
X518048Y-84564D01*
X518703Y-86023D01*
G01X516083Y-90981D02*
X511716D01*
G01X529653Y-93606D02*
X536640D01*
X535985Y-91564D01*
X534893Y-90398D01*
X533365Y-89815D01*
X531836Y-90106D01*
X530526Y-90981D01*
X529653Y-93023D01*
X529216Y-94773D01*
Y-96523D01*
X529653Y-98273D01*
X530745Y-100023D01*
X532055Y-101189D01*
X533583Y-101481D01*
X535111Y-100898D01*
X536640Y-99148D01*
G01X547371Y-101481D02*
Y-89815D01*
G01Y-92148D02*
X548463Y-90981D01*
X549555Y-90106D01*
X551083Y-89815D01*
X552174Y-90106D01*
X553485Y-90981D01*
G01X564653Y-93606D02*
X571640D01*
X570985Y-91564D01*
X569893Y-90398D01*
X568365Y-89815D01*
X566836Y-90106D01*
X565526Y-90981D01*
X564653Y-93023D01*
X564216Y-94773D01*
Y-96523D01*
X564653Y-98273D01*
X565745Y-100023D01*
X567055Y-101189D01*
X568583Y-101481D01*
X570111Y-100898D01*
X571640Y-99148D01*
G01X581716Y-101481D02*
Y-89815D01*
G01Y-92731D02*
X582590Y-91273D01*
X583900Y-90106D01*
X585646Y-89815D01*
X587174Y-90106D01*
X588485Y-91273D01*
X589140Y-93314D01*
Y-101481D01*
G01X606421Y-91273D02*
X604893Y-90106D01*
X603583Y-89815D01*
X601836Y-90398D01*
X600526Y-91564D01*
X599653Y-93606D01*
X599434Y-95648D01*
X599653Y-97690D01*
X600526Y-99440D01*
X601836Y-100898D01*
X603583Y-101481D01*
X605111Y-100898D01*
X606421Y-99731D01*
G01X617153Y-93606D02*
X624140D01*
X623485Y-91564D01*
X622393Y-90398D01*
X620865Y-89815D01*
X619336Y-90106D01*
X618026Y-90981D01*
X617153Y-93023D01*
X616716Y-94773D01*
Y-96523D01*
X617153Y-98273D01*
X618245Y-100023D01*
X619555Y-101189D01*
X621083Y-101481D01*
X622611Y-100898D01*
X624140Y-99148D01*
G01X655428Y-83981D02*
Y-101481D01*
G01X652371Y-89815D02*
X658485D01*
G01X672928Y-101481D02*
X671618Y-101189D01*
X670308Y-100023D01*
X669434Y-97981D01*
X668998Y-95648D01*
X669434Y-93314D01*
X670308Y-91273D01*
X671618Y-90106D01*
X672928Y-89815D01*
X674238Y-90106D01*
X675548Y-91273D01*
X676421Y-93314D01*
X676640Y-95648D01*
X676421Y-97981D01*
X675548Y-100023D01*
X674238Y-101189D01*
X672928Y-101481D01*
G01X706618D02*
Y-86606D01*
X707055Y-85148D01*
X707928Y-84273D01*
X709238Y-83981D01*
X710548Y-84564D01*
X711203Y-86023D01*
G01X708583Y-90981D02*
X704216D01*
G01X725428Y-89815D02*
Y-101481D01*
G01Y-85148D02*
X724991Y-84856D01*
Y-84273D01*
X725428Y-83981D01*
X725865Y-84273D01*
Y-84856D01*
X725428Y-85148D01*
G01X739216Y-101481D02*
Y-89815D01*
G01Y-92731D02*
X740090Y-91273D01*
X741400Y-90106D01*
X743146Y-89815D01*
X744674Y-90106D01*
X745985Y-91273D01*
X746640Y-93314D01*
Y-101481D01*
G01X764358Y-83981D02*
Y-101481D01*
G01Y-98857D02*
X763485Y-100315D01*
X762174Y-101189D01*
X760646Y-101481D01*
X758900Y-100898D01*
X757590Y-99440D01*
X756716Y-97690D01*
X756498Y-95648D01*
X756716Y-93606D01*
X757590Y-91856D01*
X758900Y-90398D01*
X760646Y-89815D01*
X762174Y-90106D01*
X763266Y-90690D01*
X764358Y-91856D01*
G01X795428Y-83981D02*
Y-101481D01*
G01X792371Y-89815D02*
X798485D01*
G01X809216Y-101481D02*
Y-83981D01*
G01Y-92439D02*
X810308Y-90981D01*
X811400Y-90106D01*
X813146Y-89815D01*
X814456Y-90106D01*
X815985Y-91273D01*
X816640Y-93023D01*
Y-101481D01*
G01X827153Y-93606D02*
X834140D01*
X833485Y-91564D01*
X832393Y-90398D01*
X830865Y-89815D01*
X829336Y-90106D01*
X828026Y-90981D01*
X827153Y-93023D01*
X826716Y-94773D01*
Y-96523D01*
X827153Y-98273D01*
X828245Y-100023D01*
X829555Y-101189D01*
X831083Y-101481D01*
X832611Y-100898D01*
X834140Y-99148D01*
G01X860843D02*
X862590Y-100606D01*
X864555Y-101481D01*
X866301D01*
X868048Y-100606D01*
X869358Y-99148D01*
X870013Y-97106D01*
X869576Y-95065D01*
X868485Y-93314D01*
X866520Y-92148D01*
X863900Y-91564D01*
X862371Y-90398D01*
X861716Y-88356D01*
X862153Y-86314D01*
X863245Y-84856D01*
X864773Y-83981D01*
X866301D01*
X867830Y-84564D01*
X869140Y-86023D01*
G01X887295Y-101481D02*
X878561D01*
Y-83981D01*
X887295D01*
G01X883801Y-92439D02*
X878561D01*
G01X917928Y-89815D02*
Y-101481D01*
G01Y-85148D02*
X917491Y-84856D01*
Y-84273D01*
X917928Y-83981D01*
X918365Y-84273D01*
Y-84856D01*
X917928Y-85148D01*
G01X928878Y-101481D02*
Y-89815D01*
G01Y-93023D02*
X929533Y-91564D01*
X930625Y-90398D01*
X932153Y-89815D01*
X933681Y-90398D01*
X934773Y-91564D01*
X935428Y-93023D01*
Y-101481D01*
G01Y-93023D02*
X936083Y-91564D01*
X937174Y-90398D01*
X938703Y-89815D01*
X940231Y-90398D01*
X941323Y-91564D01*
X941978Y-93314D01*
Y-101481D01*
G01X948998Y-107314D02*
Y-89815D01*
G01Y-92439D02*
X950090Y-90981D01*
X951181Y-90106D01*
X952928Y-89815D01*
X954456Y-90106D01*
X955985Y-91564D01*
X956640Y-93606D01*
X956858Y-95648D01*
X956640Y-97690D01*
X955985Y-99731D01*
X954674Y-100898D01*
X952928Y-101481D01*
X951400Y-101189D01*
X949871Y-100315D01*
X948998Y-99148D01*
G01X967153Y-93606D02*
X974140D01*
X973485Y-91564D01*
X972393Y-90398D01*
X970865Y-89815D01*
X969336Y-90106D01*
X968026Y-90981D01*
X967153Y-93023D01*
X966716Y-94773D01*
Y-96523D01*
X967153Y-98273D01*
X968245Y-100023D01*
X969555Y-101189D01*
X971083Y-101481D01*
X972611Y-100898D01*
X974140Y-99148D01*
G01X991858Y-83981D02*
Y-101481D01*
G01Y-98857D02*
X990985Y-100315D01*
X989674Y-101189D01*
X988146Y-101481D01*
X986400Y-100898D01*
X985090Y-99440D01*
X984216Y-97690D01*
X983998Y-95648D01*
X984216Y-93606D01*
X985090Y-91856D01*
X986400Y-90398D01*
X988146Y-89815D01*
X989674Y-90106D01*
X990766Y-90690D01*
X991858Y-91856D01*
G01X1009358Y-101481D02*
Y-89815D01*
G01Y-91856D02*
X1008485Y-90690D01*
X1007174Y-90106D01*
X1005646Y-89815D01*
X1004118Y-90398D01*
X1002808Y-91564D01*
X1001934Y-93314D01*
X1001498Y-95648D01*
X1001934Y-97981D01*
X1002808Y-99731D01*
X1004118Y-100898D01*
X1005646Y-101481D01*
X1007174Y-101189D01*
X1008485Y-100315D01*
X1009358Y-99148D01*
G01X1019216Y-101481D02*
Y-89815D01*
G01Y-92731D02*
X1020090Y-91273D01*
X1021400Y-90106D01*
X1023146Y-89815D01*
X1024674Y-90106D01*
X1025985Y-91273D01*
X1026640Y-93314D01*
Y-101481D01*
G01X1043921Y-91273D02*
X1042393Y-90106D01*
X1041083Y-89815D01*
X1039336Y-90398D01*
X1038026Y-91564D01*
X1037153Y-93606D01*
X1036934Y-95648D01*
X1037153Y-97690D01*
X1038026Y-99440D01*
X1039336Y-100898D01*
X1041083Y-101481D01*
X1042611Y-100898D01*
X1043921Y-99731D01*
G01X1054653Y-93606D02*
X1061640D01*
X1060985Y-91564D01*
X1059893Y-90398D01*
X1058365Y-89815D01*
X1056836Y-90106D01*
X1055526Y-90981D01*
X1054653Y-93023D01*
X1054216Y-94773D01*
Y-96523D01*
X1054653Y-98273D01*
X1055745Y-100023D01*
X1057055Y-101189D01*
X1058583Y-101481D01*
X1060111Y-100898D01*
X1061640Y-99148D01*
G01X1092928Y-83981D02*
Y-101481D01*
G01X1089871Y-89815D02*
X1095985D01*
G01X1107371Y-101481D02*
Y-89815D01*
G01Y-92148D02*
X1108463Y-90981D01*
X1109555Y-90106D01*
X1111083Y-89815D01*
X1112174Y-90106D01*
X1113485Y-90981D01*
G01X1131858Y-101481D02*
Y-89815D01*
G01Y-91856D02*
X1130985Y-90690D01*
X1129674Y-90106D01*
X1128146Y-89815D01*
X1126618Y-90398D01*
X1125308Y-91564D01*
X1124434Y-93314D01*
X1123998Y-95648D01*
X1124434Y-97981D01*
X1125308Y-99731D01*
X1126618Y-100898D01*
X1128146Y-101481D01*
X1129674Y-101189D01*
X1130985Y-100315D01*
X1131858Y-99148D01*
G01X1148921Y-91273D02*
X1147393Y-90106D01*
X1146083Y-89815D01*
X1144336Y-90398D01*
X1143026Y-91564D01*
X1142153Y-93606D01*
X1141934Y-95648D01*
X1142153Y-97690D01*
X1143026Y-99440D01*
X1144336Y-100898D01*
X1146083Y-101481D01*
X1147611Y-100898D01*
X1148921Y-99731D01*
G01X1159653Y-93606D02*
X1166640D01*
X1165985Y-91564D01*
X1164893Y-90398D01*
X1163365Y-89815D01*
X1161836Y-90106D01*
X1160526Y-90981D01*
X1159653Y-93023D01*
X1159216Y-94773D01*
Y-96523D01*
X1159653Y-98273D01*
X1160745Y-100023D01*
X1162055Y-101189D01*
X1163583Y-101481D01*
X1165111Y-100898D01*
X1166640Y-99148D01*
G01X1177153Y-99440D02*
X1178245Y-100606D01*
X1179773Y-101481D01*
X1181083D01*
X1182393Y-100898D01*
X1183266Y-100023D01*
X1183703Y-98857D01*
X1183485Y-97106D01*
X1182611Y-96231D01*
X1178681Y-94481D01*
X1177808Y-92439D01*
X1178245Y-90981D01*
X1179118Y-90106D01*
X1180428Y-89815D01*
X1181738Y-90106D01*
X1183048Y-90981D01*
G01X1215428Y-89815D02*
Y-101481D01*
G01Y-85148D02*
X1214991Y-84856D01*
Y-84273D01*
X1215428Y-83981D01*
X1215865Y-84273D01*
Y-84856D01*
X1215428Y-85148D01*
G01X1229216Y-101481D02*
Y-89815D01*
G01Y-92731D02*
X1230090Y-91273D01*
X1231400Y-90106D01*
X1233146Y-89815D01*
X1234674Y-90106D01*
X1235985Y-91273D01*
X1236640Y-93314D01*
Y-101481D01*
G01X1267928D02*
Y-83981D01*
G01X1289358Y-101481D02*
Y-89815D01*
G01Y-91856D02*
X1288485Y-90690D01*
X1287174Y-90106D01*
X1285646Y-89815D01*
X1284118Y-90398D01*
X1282808Y-91564D01*
X1281934Y-93314D01*
X1281498Y-95648D01*
X1281934Y-97981D01*
X1282808Y-99731D01*
X1284118Y-100898D01*
X1285646Y-101481D01*
X1287174Y-101189D01*
X1288485Y-100315D01*
X1289358Y-99148D01*
G01X1298343Y-106731D02*
X1299653Y-107314D01*
X1301400Y-106731D01*
X1302491Y-105565D01*
X1303365Y-104106D01*
X1304674Y-99440D01*
X1307513Y-89815D01*
G01X1300526D02*
X1304674Y-99440D01*
G01X1317153Y-93606D02*
X1324140D01*
X1323485Y-91564D01*
X1322393Y-90398D01*
X1320865Y-89815D01*
X1319336Y-90106D01*
X1318026Y-90981D01*
X1317153Y-93023D01*
X1316716Y-94773D01*
Y-96523D01*
X1317153Y-98273D01*
X1318245Y-100023D01*
X1319555Y-101189D01*
X1321083Y-101481D01*
X1322611Y-100898D01*
X1324140Y-99148D01*
G01X1334871Y-101481D02*
Y-89815D01*
G01Y-92148D02*
X1335963Y-90981D01*
X1337055Y-90106D01*
X1338583Y-89815D01*
X1339674Y-90106D01*
X1340985Y-90981D01*
G01X1368561Y-83981D02*
Y-101481D01*
X1377295D01*
G01X1385625Y-97981D02*
X1386934Y-100023D01*
X1388681Y-101189D01*
X1390646Y-101481D01*
X1392393Y-101189D01*
X1394140Y-99731D01*
X1395231Y-97981D01*
X1395450Y-96231D01*
X1395013Y-94190D01*
X1393485Y-92731D01*
X1391956Y-92148D01*
X1389991D01*
G01X1391956D02*
X1393266Y-91273D01*
X1394358Y-89815D01*
X1394795Y-88065D01*
X1394358Y-86314D01*
X1393266Y-84856D01*
X1391301Y-83981D01*
X1389336Y-84273D01*
X1387371Y-85440D01*
G01X1407928Y-102064D02*
X1407491Y-101773D01*
Y-101189D01*
X1407928Y-100898D01*
X1408365Y-101189D01*
Y-101773D01*
X1407928Y-102064D01*
G01X1481935Y875371D02*
X1483682Y873913D01*
X1485647Y873038D01*
X1487393D01*
X1489140Y873913D01*
X1490450Y875371D01*
X1491105Y877413D01*
X1490668Y879454D01*
X1489577Y881205D01*
X1487612Y882371D01*
X1484992Y882955D01*
X1483463Y884121D01*
X1482808Y886163D01*
X1483245Y888205D01*
X1484337Y889663D01*
X1485865Y890538D01*
X1487393D01*
X1488922Y889955D01*
X1490232Y888496D01*
G01X1508387Y873038D02*
X1499653D01*
Y890538D01*
X1508387D01*
G01X1504893Y882080D02*
X1499653D01*
G01X1536400Y890538D02*
X1541640D01*
G01X1539020D02*
Y873038D01*
G01X1536400D02*
X1541640D01*
G01X1550843D02*
Y890538D01*
X1556520Y875955D01*
X1562197Y890538D01*
Y873038D01*
G01X1569653D02*
Y890538D01*
X1574893D01*
X1576640Y889663D01*
X1577950Y887621D01*
X1578387Y885288D01*
X1577950Y882955D01*
X1576858Y881205D01*
X1574893Y880329D01*
X1569653D01*
G01X1595887Y873038D02*
X1587153D01*
Y890538D01*
X1595887D01*
G01X1592393Y882080D02*
X1587153D01*
G01X1604217Y873038D02*
Y890538D01*
X1608583D01*
X1610330Y889663D01*
X1611640Y888496D01*
X1612732Y886747D01*
X1613605Y884704D01*
X1613823Y881788D01*
X1613605Y878871D01*
X1612732Y876829D01*
X1611640Y875079D01*
X1610330Y873913D01*
X1608583Y873038D01*
X1604217D01*
G01X1621061D02*
X1626520Y890538D01*
X1631979Y873038D01*
G01X1630013Y879163D02*
X1623026D01*
G01X1638998Y873038D02*
Y890538D01*
X1649042Y873038D01*
Y890538D01*
G01X1666323Y889079D02*
X1665013Y889955D01*
X1663485Y890538D01*
X1661738D01*
X1659773Y889663D01*
X1658245Y888205D01*
X1657153Y886454D01*
X1656280Y883538D01*
X1656061Y880913D01*
X1656498Y878288D01*
X1657153Y876538D01*
X1658463Y874788D01*
X1659992Y873621D01*
X1661520Y873038D01*
X1663048D01*
X1664577Y873621D01*
X1665887Y874496D01*
X1666979Y875662D01*
G01X1683387Y873038D02*
X1674653D01*
Y890538D01*
X1683387D01*
G01X1679893Y882080D02*
X1674653D01*
G01X1714020Y890538D02*
Y873038D01*
G01X1708998Y890538D02*
X1719042D01*
G01X1726061Y873038D02*
X1731520Y890538D01*
X1736979Y873038D01*
G01X1735013Y879163D02*
X1728026D01*
G01X1750766Y882371D02*
X1751640Y883246D01*
X1752295Y884704D01*
X1752732Y886747D01*
X1752295Y888496D01*
X1751422Y889663D01*
X1749893Y890538D01*
X1743998D01*
Y873038D01*
X1751203D01*
X1752732Y874204D01*
X1753605Y875955D01*
X1754042Y877996D01*
X1753605Y880038D01*
X1752295Y881788D01*
X1750766Y882371D01*
X1743998D01*
G01X1762153Y890538D02*
Y873038D01*
X1770887D01*
G01X1788387D02*
X1779653D01*
Y890538D01*
X1788387D01*
G01X1784893Y882080D02*
X1779653D01*
G01X1801520Y872455D02*
X1801083Y872746D01*
Y873330D01*
X1801520Y873621D01*
X1801957Y873330D01*
Y872746D01*
X1801520Y872455D01*
G01Y880329D02*
X1801083Y880621D01*
Y881205D01*
X1801520Y881496D01*
X1801957Y881205D01*
Y880621D01*
X1801520Y880329D01*
G01X1832153Y890538D02*
Y873038D01*
X1840887D01*
G01X1849217Y876538D02*
X1850526Y874496D01*
X1852273Y873330D01*
X1854238Y873038D01*
X1855985Y873330D01*
X1857732Y874788D01*
X1858823Y876538D01*
X1859042Y878288D01*
X1858605Y880329D01*
X1857077Y881788D01*
X1855548Y882371D01*
X1853583D01*
G01X1855548D02*
X1856858Y883246D01*
X1857950Y884704D01*
X1858387Y886454D01*
X1857950Y888205D01*
X1856858Y889663D01*
X1854893Y890538D01*
X1852928Y890246D01*
X1850963Y889079D01*
G01X1503600Y855888D02*
X1508840D01*
G01X1506220D02*
Y838388D01*
G01X1503600D02*
X1508840D01*
G01X1518043D02*
Y855888D01*
X1523720Y841305D01*
X1529397Y855888D01*
Y838388D01*
G01X1536853D02*
Y855888D01*
X1542093D01*
X1543840Y855013D01*
X1545150Y852971D01*
X1545587Y850638D01*
X1545150Y848305D01*
X1544058Y846555D01*
X1542093Y845679D01*
X1536853D01*
G01X1557628Y832555D02*
X1555445Y835471D01*
X1554353Y838388D01*
Y850054D01*
X1555445Y852971D01*
X1557628Y855888D01*
G01X1576220Y838388D02*
X1574473Y838680D01*
X1572945Y839846D01*
X1571635Y841596D01*
X1570761Y843638D01*
X1570325Y845971D01*
Y848305D01*
X1570761Y850638D01*
X1571635Y852680D01*
X1572945Y854429D01*
X1574473Y855596D01*
X1576220Y855888D01*
X1577966Y855596D01*
X1579495Y854429D01*
X1580805Y852680D01*
X1581679Y850638D01*
X1582115Y848305D01*
Y845971D01*
X1581679Y843638D01*
X1580805Y841596D01*
X1579495Y839846D01*
X1577966Y838680D01*
X1576220Y838388D01*
G01X1590008D02*
Y855888D01*
G01Y847430D02*
X1591100Y848888D01*
X1592192Y849763D01*
X1593938Y850054D01*
X1595248Y849763D01*
X1596777Y848596D01*
X1597432Y846846D01*
Y838388D01*
G01X1604670D02*
Y850054D01*
G01Y846846D02*
X1605325Y848305D01*
X1606417Y849471D01*
X1607945Y850054D01*
X1609473Y849471D01*
X1610565Y848305D01*
X1611220Y846846D01*
Y838388D01*
G01Y846846D02*
X1611875Y848305D01*
X1612966Y849471D01*
X1614495Y850054D01*
X1616023Y849471D01*
X1617115Y848305D01*
X1617770Y846555D01*
Y838388D01*
G01X1629812Y832555D02*
X1631995Y835471D01*
X1633087Y838388D01*
Y850054D01*
X1631995Y852971D01*
X1629812Y855888D01*
G01X1536417Y806362D02*
X1537726Y804904D01*
X1539255Y804030D01*
X1541220Y803738D01*
X1543185Y804321D01*
X1544713Y805488D01*
X1545805Y807529D01*
X1546023Y809863D01*
X1545587Y812196D01*
X1544495Y813655D01*
X1542966Y814821D01*
X1541438Y815113D01*
X1539910Y814821D01*
X1537945Y813655D01*
X1538600Y821238D01*
X1544495D01*
G01X1558720D02*
X1556973Y820655D01*
X1555663Y819196D01*
X1554790Y817447D01*
X1554135Y815113D01*
X1553917Y812488D01*
X1554135Y809863D01*
X1554790Y807529D01*
X1555663Y805779D01*
X1556973Y804321D01*
X1558720Y803738D01*
X1560466Y804321D01*
X1561777Y805779D01*
X1562650Y807529D01*
X1563305Y809863D01*
X1563523Y812488D01*
X1563305Y815113D01*
X1562650Y817447D01*
X1561777Y819196D01*
X1560466Y820655D01*
X1558720Y821238D01*
G01X1576220Y803155D02*
X1575783Y803446D01*
Y804030D01*
X1576220Y804321D01*
X1576657Y804030D01*
Y803446D01*
X1576220Y803155D01*
G01X1593720Y821238D02*
X1591973Y820655D01*
X1590663Y819196D01*
X1589790Y817447D01*
X1589135Y815113D01*
X1588917Y812488D01*
X1589135Y809863D01*
X1589790Y807529D01*
X1590663Y805779D01*
X1591973Y804321D01*
X1593720Y803738D01*
X1595466Y804321D01*
X1596777Y805779D01*
X1597650Y807529D01*
X1598305Y809863D01*
X1598523Y812488D01*
X1598305Y815113D01*
X1597650Y817447D01*
X1596777Y819196D01*
X1595466Y820655D01*
X1593720Y821238D01*
G01X1674670Y855888D02*
X1677726Y838388D01*
X1681220Y855888D01*
X1684713Y838388D01*
X1687770Y855888D01*
G01X1696100D02*
X1701340D01*
G01X1698720D02*
Y838388D01*
G01X1696100D02*
X1701340D01*
G01X1711417D02*
Y855888D01*
X1715783D01*
X1717530Y855013D01*
X1718840Y853846D01*
X1719932Y852097D01*
X1720805Y850054D01*
X1721023Y847138D01*
X1720805Y844221D01*
X1719932Y842179D01*
X1718840Y840429D01*
X1717530Y839263D01*
X1715783Y838388D01*
X1711417D01*
G01X1733720Y855888D02*
Y838388D01*
G01X1728698Y855888D02*
X1738742D01*
G01X1746635Y838388D02*
Y855888D01*
G01X1755805D02*
Y838388D01*
G01Y847138D02*
X1746635D01*
G01X1767628Y832555D02*
X1765445Y835471D01*
X1764353Y838388D01*
Y850054D01*
X1765445Y852971D01*
X1767628Y855888D01*
G01X1779670Y838388D02*
Y850054D01*
G01Y846846D02*
X1780325Y848305D01*
X1781417Y849471D01*
X1782945Y850054D01*
X1784473Y849471D01*
X1785565Y848305D01*
X1786220Y846846D01*
Y838388D01*
G01Y846846D02*
X1786875Y848305D01*
X1787966Y849471D01*
X1789495Y850054D01*
X1791023Y849471D01*
X1792115Y848305D01*
X1792770Y846555D01*
Y838388D01*
G01X1803720Y850054D02*
Y838388D01*
G01Y854721D02*
X1803283Y855013D01*
Y855596D01*
X1803720Y855888D01*
X1804157Y855596D01*
Y855013D01*
X1803720Y854721D01*
G01X1821220Y838388D02*
Y855888D01*
G01X1835445Y840429D02*
X1836537Y839263D01*
X1838065Y838388D01*
X1839375D01*
X1840685Y838971D01*
X1841558Y839846D01*
X1841995Y841012D01*
X1841777Y842763D01*
X1840903Y843638D01*
X1836973Y845388D01*
X1836100Y847430D01*
X1836537Y848888D01*
X1837410Y849763D01*
X1838720Y850054D01*
X1840030Y849763D01*
X1841340Y848888D01*
G01X1857312Y832555D02*
X1859495Y835471D01*
X1860587Y838388D01*
Y850054D01*
X1859495Y852971D01*
X1857312Y855888D01*
G01X1746417Y806362D02*
X1747726Y804904D01*
X1749255Y804030D01*
X1751220Y803738D01*
X1753185Y804321D01*
X1754713Y805488D01*
X1755805Y807529D01*
X1756023Y809863D01*
X1755587Y812196D01*
X1754495Y813655D01*
X1752966Y814821D01*
X1751438Y815113D01*
X1749910Y814821D01*
X1747945Y813655D01*
X1748600Y821238D01*
X1754495D01*
G01X1768720Y803155D02*
X1768283Y803446D01*
Y804030D01*
X1768720Y804321D01*
X1769157Y804030D01*
Y803446D01*
X1768720Y803155D01*
G01X1786220Y821238D02*
X1784473Y820655D01*
X1783163Y819196D01*
X1782290Y817447D01*
X1781635Y815113D01*
X1781417Y812488D01*
X1781635Y809863D01*
X1782290Y807529D01*
X1783163Y805779D01*
X1784473Y804321D01*
X1786220Y803738D01*
X1787966Y804321D01*
X1789277Y805779D01*
X1790150Y807529D01*
X1790805Y809863D01*
X1791023Y812488D01*
X1790805Y815113D01*
X1790150Y817447D01*
X1789277Y819196D01*
X1787966Y820655D01*
X1786220Y821238D01*
G01X1908720Y855888D02*
Y838388D01*
G01X1903698Y855888D02*
X1913742D01*
G01X1926220Y838388D02*
Y846263D01*
X1921853Y855888D01*
G01X1930587D02*
X1926220Y846263D01*
G01X1939353Y838388D02*
Y855888D01*
X1944593D01*
X1946340Y855013D01*
X1947650Y852971D01*
X1948087Y850638D01*
X1947650Y848305D01*
X1946558Y846555D01*
X1944593Y845679D01*
X1939353D01*
G01X1965587Y838388D02*
X1956853D01*
Y855888D01*
X1965587D01*
G01X1962093Y847430D02*
X1956853D01*
G01X1921635Y806071D02*
X1923382Y804613D01*
X1925347Y803738D01*
X1927093D01*
X1928840Y804613D01*
X1930150Y806071D01*
X1930805Y808113D01*
X1930368Y810154D01*
X1929277Y811905D01*
X1927312Y813071D01*
X1924692Y813655D01*
X1923163Y814821D01*
X1922508Y816863D01*
X1922945Y818905D01*
X1924037Y820363D01*
X1925565Y821238D01*
X1927093D01*
X1928622Y820655D01*
X1929932Y819196D01*
G01X1948087Y803738D02*
X1939353D01*
Y821238D01*
X1948087D01*
G01X1944593Y812780D02*
X1939353D01*
G01X2009353Y838388D02*
Y855888D01*
X2014812D01*
X2016558Y855013D01*
X2017650Y853846D01*
X2018087Y851513D01*
X2017650Y849179D01*
X2016340Y847721D01*
X2014812Y846846D01*
X2009353D01*
G01X2014812D02*
X2018087Y838388D01*
G01X2027945Y846263D02*
X2034932D01*
X2034277Y848305D01*
X2033185Y849471D01*
X2031657Y850054D01*
X2030128Y849763D01*
X2028818Y848888D01*
X2027945Y846846D01*
X2027508Y845096D01*
Y843346D01*
X2027945Y841596D01*
X2029037Y839846D01*
X2030347Y838680D01*
X2031875Y838388D01*
X2033403Y838971D01*
X2034932Y840721D01*
G01X2047410Y838388D02*
Y853263D01*
X2047847Y854721D01*
X2048720Y855596D01*
X2050030Y855888D01*
X2051340Y855305D01*
X2051995Y853846D01*
G01X2049375Y848888D02*
X2045008D01*
G01X2066220Y837805D02*
X2065783Y838096D01*
Y838680D01*
X2066220Y838971D01*
X2066657Y838680D01*
Y838096D01*
X2066220Y837805D01*
G01X2096853Y838388D02*
Y855888D01*
X2102093D01*
X2103840Y855013D01*
X2105150Y852971D01*
X2105587Y850638D01*
X2105150Y848305D01*
X2104058Y846555D01*
X2102093Y845679D01*
X2096853D01*
G01X2118720Y838388D02*
Y855888D01*
G01X2140150Y838388D02*
Y850054D01*
G01Y848013D02*
X2139277Y849179D01*
X2137966Y849763D01*
X2136438Y850054D01*
X2134910Y849471D01*
X2133600Y848305D01*
X2132726Y846555D01*
X2132290Y844221D01*
X2132726Y841888D01*
X2133600Y840138D01*
X2134910Y838971D01*
X2136438Y838388D01*
X2137966Y838680D01*
X2139277Y839554D01*
X2140150Y840721D01*
G01X2150008Y838388D02*
Y850054D01*
G01Y847138D02*
X2150882Y848596D01*
X2152192Y849763D01*
X2153938Y850054D01*
X2155466Y849763D01*
X2156777Y848596D01*
X2157432Y846555D01*
Y838388D01*
G01X2167945Y846263D02*
X2174932D01*
X2174277Y848305D01*
X2173185Y849471D01*
X2171657Y850054D01*
X2170128Y849763D01*
X2168818Y848888D01*
X2167945Y846846D01*
X2167508Y845096D01*
Y843346D01*
X2167945Y841596D01*
X2169037Y839846D01*
X2170347Y838680D01*
X2171875Y838388D01*
X2173403Y838971D01*
X2174932Y840721D01*
G01X2053103Y821238D02*
Y803738D01*
X2061837D01*
G01X2070822Y818321D02*
X2072132Y820071D01*
X2073660Y820946D01*
X2075407Y821238D01*
X2077590Y820655D01*
X2079118Y819196D01*
X2079555Y817447D01*
X2079337Y815696D01*
X2078463Y814238D01*
X2074097Y811321D01*
X2072132Y809280D01*
X2070822Y806362D01*
X2070385Y803738D01*
X2079555D01*
G01X2088540Y803155D02*
X2096400Y821238D01*
G01X2105603D02*
Y803738D01*
X2114337D01*
G01X2130090D02*
Y821238D01*
X2122011Y808696D01*
X2132929D01*
G01X2289020Y815404D02*
Y803738D01*
G01Y820071D02*
X2288583Y820363D01*
Y820946D01*
X2289020Y821238D01*
X2289457Y820946D01*
Y820363D01*
X2289020Y820071D01*
G01X2303245Y805779D02*
X2304337Y804613D01*
X2305865Y803738D01*
X2307175D01*
X2308485Y804321D01*
X2309358Y805196D01*
X2309795Y806362D01*
X2309577Y808113D01*
X2308703Y808988D01*
X2304773Y810738D01*
X2303900Y812780D01*
X2304337Y814238D01*
X2305210Y815113D01*
X2306520Y815404D01*
X2307830Y815113D01*
X2309140Y814238D01*
G01X2336498Y803738D02*
Y821238D01*
X2346542Y803738D01*
Y821238D01*
G01X2359020Y803738D02*
X2357273Y804030D01*
X2355745Y805196D01*
X2354435Y806946D01*
X2353561Y808988D01*
X2353125Y811321D01*
Y813655D01*
X2353561Y815988D01*
X2354435Y818030D01*
X2355745Y819779D01*
X2357273Y820946D01*
X2359020Y821238D01*
X2360766Y820946D01*
X2362295Y819779D01*
X2363605Y818030D01*
X2364479Y815988D01*
X2364915Y813655D01*
Y811321D01*
X2364479Y808988D01*
X2363605Y806946D01*
X2362295Y805196D01*
X2360766Y804030D01*
X2359020Y803738D01*
G01X2376520Y821238D02*
Y803738D01*
G01X2371498Y821238D02*
X2381542D01*
G01X2407808Y815404D02*
Y807238D01*
X2408682Y805196D01*
X2409992Y804030D01*
X2411520Y803738D01*
X2413048Y804030D01*
X2414358Y805196D01*
X2415232Y807238D01*
G01Y803738D02*
Y815404D01*
G01X2425745Y805779D02*
X2426837Y804613D01*
X2428365Y803738D01*
X2429675D01*
X2430985Y804321D01*
X2431858Y805196D01*
X2432295Y806362D01*
X2432077Y808113D01*
X2431203Y808988D01*
X2427273Y810738D01*
X2426400Y812780D01*
X2426837Y814238D01*
X2427710Y815113D01*
X2429020Y815404D01*
X2430330Y815113D01*
X2431640Y814238D01*
G01X2443245Y811613D02*
X2450232D01*
X2449577Y813655D01*
X2448485Y814821D01*
X2446957Y815404D01*
X2445428Y815113D01*
X2444118Y814238D01*
X2443245Y812196D01*
X2442808Y810446D01*
Y808696D01*
X2443245Y806946D01*
X2444337Y805196D01*
X2445647Y804030D01*
X2447175Y803738D01*
X2448703Y804321D01*
X2450232Y806071D01*
G01X2467950Y821238D02*
Y803738D01*
G01Y806362D02*
X2467077Y804904D01*
X2465766Y804030D01*
X2464238Y803738D01*
X2462492Y804321D01*
X2461182Y805779D01*
X2460308Y807529D01*
X2460090Y809571D01*
X2460308Y811613D01*
X2461182Y813363D01*
X2462492Y814821D01*
X2464238Y815404D01*
X2465766Y815113D01*
X2466858Y814529D01*
X2467950Y813363D01*
G01X2214217Y837805D02*
X2223823Y850638D01*
G01X2219020Y852971D02*
Y835471D01*
G01X2223823Y837805D02*
X2214217Y850638D01*
G01X2212470Y844221D02*
X2225570D01*
G01X2251182D02*
X2256858D01*
G01X2284217Y838388D02*
Y855888D01*
X2288583D01*
X2290330Y855013D01*
X2291640Y853846D01*
X2292732Y852097D01*
X2293605Y850054D01*
X2293823Y847138D01*
X2293605Y844221D01*
X2292732Y842179D01*
X2291640Y840429D01*
X2290330Y839263D01*
X2288583Y838388D01*
X2284217D01*
G01X2303245Y846263D02*
X2310232D01*
X2309577Y848305D01*
X2308485Y849471D01*
X2306957Y850054D01*
X2305428Y849763D01*
X2304118Y848888D01*
X2303245Y846846D01*
X2302808Y845096D01*
Y843346D01*
X2303245Y841596D01*
X2304337Y839846D01*
X2305647Y838680D01*
X2307175Y838388D01*
X2308703Y838971D01*
X2310232Y840721D01*
G01X2320308Y838388D02*
Y850054D01*
G01Y847138D02*
X2321182Y848596D01*
X2322492Y849763D01*
X2324238Y850054D01*
X2325766Y849763D01*
X2327077Y848596D01*
X2327732Y846555D01*
Y838388D01*
G01X2341520D02*
X2340210Y838680D01*
X2338900Y839846D01*
X2338026Y841888D01*
X2337590Y844221D01*
X2338026Y846555D01*
X2338900Y848596D01*
X2340210Y849763D01*
X2341520Y850054D01*
X2342830Y849763D01*
X2344140Y848596D01*
X2345013Y846555D01*
X2345232Y844221D01*
X2345013Y841888D01*
X2344140Y839846D01*
X2342830Y838680D01*
X2341520Y838388D01*
G01X2359020Y855888D02*
Y838388D01*
G01X2355963Y850054D02*
X2362077D01*
G01X2373245Y846263D02*
X2380232D01*
X2379577Y848305D01*
X2378485Y849471D01*
X2376957Y850054D01*
X2375428Y849763D01*
X2374118Y848888D01*
X2373245Y846846D01*
X2372808Y845096D01*
Y843346D01*
X2373245Y841596D01*
X2374337Y839846D01*
X2375647Y838680D01*
X2377175Y838388D01*
X2378703Y838971D01*
X2380232Y840721D01*
G01X2390745Y840429D02*
X2391837Y839263D01*
X2393365Y838388D01*
X2394675D01*
X2395985Y838971D01*
X2396858Y839846D01*
X2397295Y841012D01*
X2397077Y842763D01*
X2396203Y843638D01*
X2392273Y845388D01*
X2391400Y847430D01*
X2391837Y848888D01*
X2392710Y849763D01*
X2394020Y850054D01*
X2395330Y849763D01*
X2396640Y848888D01*
G01X2429020Y855888D02*
Y838388D01*
G01X2425963Y850054D02*
X2432077D01*
G01X2442808Y838388D02*
Y855888D01*
G01Y847430D02*
X2443900Y848888D01*
X2444992Y849763D01*
X2446738Y850054D01*
X2448048Y849763D01*
X2449577Y848596D01*
X2450232Y846846D01*
Y838388D01*
G01X2467950D02*
Y850054D01*
G01Y848013D02*
X2467077Y849179D01*
X2465766Y849763D01*
X2464238Y850054D01*
X2462710Y849471D01*
X2461400Y848305D01*
X2460526Y846555D01*
X2460090Y844221D01*
X2460526Y841888D01*
X2461400Y840138D01*
X2462710Y838971D01*
X2464238Y838388D01*
X2465766Y838680D01*
X2467077Y839554D01*
X2467950Y840721D01*
G01X2481520Y855888D02*
Y838388D01*
G01X2478463Y850054D02*
X2484577D01*
G01X2516520Y855888D02*
Y838388D01*
G01X2513463Y850054D02*
X2519577D01*
G01X2530308Y838388D02*
Y855888D01*
G01Y847430D02*
X2531400Y848888D01*
X2532492Y849763D01*
X2534238Y850054D01*
X2535548Y849763D01*
X2537077Y848596D01*
X2537732Y846846D01*
Y838388D01*
G01X2551520Y850054D02*
Y838388D01*
G01Y854721D02*
X2551083Y855013D01*
Y855596D01*
X2551520Y855888D01*
X2551957Y855596D01*
Y855013D01*
X2551520Y854721D01*
G01X2565745Y840429D02*
X2566837Y839263D01*
X2568365Y838388D01*
X2569675D01*
X2570985Y838971D01*
X2571858Y839846D01*
X2572295Y841012D01*
X2572077Y842763D01*
X2571203Y843638D01*
X2567273Y845388D01*
X2566400Y847430D01*
X2566837Y848888D01*
X2567710Y849763D01*
X2569020Y850054D01*
X2570330Y849763D01*
X2571640Y848888D01*
G01X2601400Y855888D02*
X2606640D01*
G01X2604020D02*
Y838388D01*
G01X2601400D02*
X2606640D01*
G01X2614970D02*
Y850054D01*
G01Y846846D02*
X2615625Y848305D01*
X2616717Y849471D01*
X2618245Y850054D01*
X2619773Y849471D01*
X2620865Y848305D01*
X2621520Y846846D01*
Y838388D01*
G01Y846846D02*
X2622175Y848305D01*
X2623266Y849471D01*
X2624795Y850054D01*
X2626323Y849471D01*
X2627415Y848305D01*
X2628070Y846555D01*
Y838388D01*
G01X2635090Y832555D02*
Y850054D01*
G01Y847430D02*
X2636182Y848888D01*
X2637273Y849763D01*
X2639020Y850054D01*
X2640548Y849763D01*
X2642077Y848305D01*
X2642732Y846263D01*
X2642950Y844221D01*
X2642732Y842179D01*
X2642077Y840138D01*
X2640766Y838971D01*
X2639020Y838388D01*
X2637492Y838680D01*
X2635963Y839554D01*
X2635090Y840721D01*
G01X2653245Y846263D02*
X2660232D01*
X2659577Y848305D01*
X2658485Y849471D01*
X2656957Y850054D01*
X2655428Y849763D01*
X2654118Y848888D01*
X2653245Y846846D01*
X2652808Y845096D01*
Y843346D01*
X2653245Y841596D01*
X2654337Y839846D01*
X2655647Y838680D01*
X2657175Y838388D01*
X2658703Y838971D01*
X2660232Y840721D01*
G01X2677950Y855888D02*
Y838388D01*
G01Y841012D02*
X2677077Y839554D01*
X2675766Y838680D01*
X2674238Y838388D01*
X2672492Y838971D01*
X2671182Y840429D01*
X2670308Y842179D01*
X2670090Y844221D01*
X2670308Y846263D01*
X2671182Y848013D01*
X2672492Y849471D01*
X2674238Y850054D01*
X2675766Y849763D01*
X2676858Y849179D01*
X2677950Y848013D01*
G01X2695450Y838388D02*
Y850054D01*
G01Y848013D02*
X2694577Y849179D01*
X2693266Y849763D01*
X2691738Y850054D01*
X2690210Y849471D01*
X2688900Y848305D01*
X2688026Y846555D01*
X2687590Y844221D01*
X2688026Y841888D01*
X2688900Y840138D01*
X2690210Y838971D01*
X2691738Y838388D01*
X2693266Y838680D01*
X2694577Y839554D01*
X2695450Y840721D01*
G01X2705308Y838388D02*
Y850054D01*
G01Y847138D02*
X2706182Y848596D01*
X2707492Y849763D01*
X2709238Y850054D01*
X2710766Y849763D01*
X2712077Y848596D01*
X2712732Y846555D01*
Y838388D01*
G01X2730013Y848596D02*
X2728485Y849763D01*
X2727175Y850054D01*
X2725428Y849471D01*
X2724118Y848305D01*
X2723245Y846263D01*
X2723026Y844221D01*
X2723245Y842179D01*
X2724118Y840429D01*
X2725428Y838971D01*
X2727175Y838388D01*
X2728703Y838971D01*
X2730013Y840138D01*
G01X2740745Y846263D02*
X2747732D01*
X2747077Y848305D01*
X2745985Y849471D01*
X2744457Y850054D01*
X2742928Y849763D01*
X2741618Y848888D01*
X2740745Y846846D01*
X2740308Y845096D01*
Y843346D01*
X2740745Y841596D01*
X2741837Y839846D01*
X2743147Y838680D01*
X2744675Y838388D01*
X2746203Y838971D01*
X2747732Y840721D01*
G01X1425733Y-51181D02*
X-29385D01*
G01X-33322Y-47244D02*
G03X-29385Y-51181I3937J0D01*
G01X-33322Y-47244D02*
Y893701D01*
G01X-7874Y102402D02*
Y212205D01*
G01Y102402D02*
G03X0Y94528I7874J0D01*
G01Y212205D02*
G03X-7874I-3937J0D01*
G01Y237402D02*
G03X0I3937J-1D01*
G01X-7874D02*
Y406693D01*
G01X0D02*
G03X-7874I-3937J0D01*
G01Y431890D02*
G03X0I3937J0D01*
G01X-7874D02*
Y601181D01*
G01X0D02*
G03X-7874I-3937J0D01*
G01Y626378D02*
Y795669D01*
G01Y626378D02*
G03X0I3937J0D01*
G01Y795669D02*
G03X-7874I-3937J0D01*
G01Y820866D02*
G03X0I3937J0D01*
G01X-7874Y844488D02*
Y820866D01*
G01X-3937Y848425D02*
G03X-7874Y844488I0J-3937D01*
G01X93307Y848425D02*
X-3937D01*
G01X-29385Y897638D02*
G03X-33322Y893701I0J-3937D01*
G01X-29385Y897638D02*
X93307D01*
G01X98425Y94528D02*
X0D01*
G01X1400000Y36220D02*
G03X1398031Y38189I-1969J0D01*
G01X1396654D01*
G02X1394685Y40157I0J1969D01*
G01Y71654D01*
G02X1396654Y73622I1969J-1D01*
G01X1398031D01*
G03X1400000Y75591I0J1969D01*
G01Y836614D01*
G03X1396063Y840551I-3937J0D01*
G01X1368504D01*
G02X1363386Y845669I0J5118D01*
G01Y871654D01*
G03X1361417Y873622I-1969J-1D01*
G01X1358268D01*
G02X1356299Y875591I0J1969D01*
G01Y892521D01*
X1352363Y897638D01*
X1218110D01*
X1214173Y892520D01*
Y875984D01*
G02X1205512I-4331J0D01*
G01Y892520D01*
X1201575Y897638D01*
X1029528D01*
X1025591Y892520D01*
Y875591D01*
G02X1023622Y873622I-1969J0D01*
G01X1020472D01*
G03X1018504Y871654I0J-1968D01*
G01Y845669D01*
G02X1013386Y840551I-5118J0D01*
G01X1008433D01*
G03X988748Y820866I0J-19685D01*
G01Y650669D01*
G02X983748Y645669I-5000J0D01*
G01X926819D01*
G02X921819Y650669I0J5000D01*
G01Y820866D01*
G03X902134Y840551I-19685J0D01*
G01X872441D01*
G02X867323Y845669I0J5118D01*
G01Y871654D01*
G03X865354Y873622I-1969J-1D01*
G01X862205D01*
G02X860236Y875591I0J1969D01*
G01Y892521D01*
X856300Y897638D01*
X722048D01*
X718110Y892519D01*
Y875984D01*
G02X709449I-4331J0D01*
G01Y892520D01*
X705512Y897638D01*
X533465D01*
X529528Y892520D01*
Y875591D01*
G02X527559Y873622I-1969J0D01*
G01X524409D01*
G03X522441Y871654I0J-1968D01*
G01Y845669D01*
G02X517323Y840551I-5118J0D01*
G01X455118D01*
G02X450000Y845669I0J5118D01*
G01Y871654D01*
G03X448031Y873622I-1968J0D01*
G01X444882D01*
G02X442913Y875591I0J1969D01*
G01Y892521D01*
X438977Y897638D01*
X304725D01*
X300787Y892519D01*
Y875984D01*
G02X292126I-4331J0D01*
G01Y892521D01*
X288190Y897638D01*
X116142D01*
X112205Y892520D01*
Y875591D01*
G02X110236Y873622I-1969J0D01*
G01X107087D01*
G03X105118Y871654I0J-1969D01*
G01Y845669D01*
G02X100000Y840551I-5118J0D01*
G01X3937D01*
G03X0Y836614I0J-3937D01*
G01Y110276D01*
G03X7874Y102402I7874J0D01*
G01X196654D01*
G02X204528Y94528I0J-7874D01*
G01Y7874D01*
G03X212402Y0I7874J0D01*
G01X471014D01*
G02X478888Y-7874I0J-7874D01*
G01Y-11811D01*
G03X486762Y-19685I7874J0D01*
G01X1302165D01*
G03X1306102Y-15748I0J3937D01*
G01Y-3937D01*
G02X1310039Y0I3937J0D01*
G01X1396063D01*
G03X1400000Y3937I0J3937D01*
G01Y36220D01*
G01X93307Y848425D02*
G03X97244Y852362I0J3937D01*
G01Y893701D02*
Y852362D01*
G01Y893701D02*
G03X93307Y897638I-3937J0D01*
G01X192717Y94528D02*
X123622D01*
G01Y102402D02*
G03Y94528I0J-3937D01*
G01X98425D02*
G03Y102402I0J3937D01*
G01X196654Y0D02*
G03X204528Y-7874I7874J0D01*
G01X196654Y0D02*
Y29961D01*
G01X204528D02*
G03X196654I-3937J0D01*
G01Y55157D02*
Y90591D01*
G01Y55157D02*
G03X204528I3937J0D01*
G01X196654Y90591D02*
G03X192717Y94528I-3937J0D01*
G01X232077Y-7874D02*
G03Y0I0J3937D01*
G01Y-7874D02*
X204528D01*
G01X434439D02*
X257274D01*
G01Y0D02*
G03Y-7874I0J-3937D01*
G01X365945Y38188D02*
G03X367914Y40156I0J1969D01*
G01X354134D02*
G03X356103Y38188I1969J1D01*
G01D02*
X365945D01*
G01X354134Y71653D02*
Y40156D01*
G01X367914Y71653D02*
G03X365945Y73621I-1969J-1D01*
G01X356103D02*
G03X354134Y71653I0J-1969D01*
G01X365945Y73621D02*
X356103D01*
G01X367914Y40156D02*
Y71653D01*
G01X434439Y-7874D02*
G03Y0I0J3937D01*
G01X471014Y-15748D02*
G03X463140Y-7874I-7874J0D01*
G01D02*
X459636D01*
G01Y0D02*
G03Y-7874I0J-3937D01*
G01X707234Y-27559D02*
X478888D01*
G01X471014Y-19685D02*
G03X478888Y-27559I7874J0D01*
G01X471014Y-19685D02*
Y-15748D01*
G01X870226Y-27559D02*
X732431D01*
G01Y-19685D02*
G03Y-27559I0J-3937D01*
G01X707234D02*
G03Y-19685I0J3937D01*
G01X870226Y-27559D02*
G03Y-19685I1J3937D01*
G01X1072589Y-27559D02*
X895423D01*
G01Y-19685D02*
G03Y-27559I0J-3937D01*
G01X1072589D02*
G03Y-19685I0J3937D01*
G01X1097785D02*
G03Y-27559I1J-3937D01*
G01X1336086Y-8662D02*
X1318701D01*
G03X1314764Y-12599I0J-3937D01*
G01Y-23622D01*
G02X1310827Y-27559I-3937J0D01*
G01X1097785D01*
G01X1336086Y-8662D02*
G03Y-1I0J4330D01*
G01X1361283D02*
G03Y-8662I0J-4330D01*
G01X1407874Y13026D02*
Y-4725D01*
G02X1403937Y-8662I-3937J0D01*
G01X1361283D01*
G01X1403937Y848425D02*
X1375197D01*
G01X1371260Y852362D02*
G03X1375197Y848425I3937J0D01*
G01X1371260Y852362D02*
Y893701D01*
G01X1375197Y897638D02*
G03X1371260Y893701I0J-3937D01*
G01X1375197Y897638D02*
X1425733D01*
G01X1407874Y30709D02*
Y219685D01*
G01X1400000Y30709D02*
G03X1407874I3937J0D01*
G01Y13026D02*
G03X1400000I-3937J-1D01*
G01X1407874Y219685D02*
G03X1400000I-3937J0D01*
G01Y244882D02*
G03X1407874I3937J0D01*
G01Y414173D02*
Y244882D01*
G01Y608661D02*
Y439370D01*
G01X1400000D02*
G03X1407874I3937J0D01*
G01Y414173D02*
G03X1400000I-3937J0D01*
G01X1407874Y608661D02*
G03X1400000I-3937J0D01*
G01Y626378D02*
G03X1407874I3937J0D01*
G01Y795669D02*
Y626378D01*
G01Y795669D02*
G03X1400000I-3937J0D01*
G01Y820866D02*
G03X1407874I3937J0D01*
G01Y844488D02*
Y820866D01*
G01Y844488D02*
G03X1403937Y848425I-3937J0D01*
G01X1429670Y893701D02*
Y-47244D01*
G01X1425733Y-51181D02*
G03X1429670Y-47244I0J3937D01*
G01Y893701D02*
G03X1425733Y897638I-3937J0D01*
M02*
